FILE_TYPE = MACRO_DRAWING;
SET COLOR_WIRE YELLOW;
SET COLOR_PROP MONO;
SET COLOR_DOT WHITE;
SET COLOR_ARC YELLOW;
SET COLOR_BODY GREEN;
SET COLOR_NOTE MONO;
SET PROP_DISPLAY VALUE;
SET PAGE_NUMBER P201;
FORCEADD OFFPAGE..2
(-450 3325);
FORCEPROP 2 LAST $XR1 190 
J 0
(-261 3289);
DISPLAY 0.638298 (-261 3289);
PAINT MONO (-261 3289);
FORCEPROP 2 LAST $XR0 112 
J 0
(-261 3325);
DISPLAY 0.638298 (-261 3325);
PAINT MONO (-261 3325);
FORCEPROP 2 LAST PATH I1
J 0
(-275 3400);
DISPLAY 1.021277 (-275 3400);
PAINT ORANGE (-275 3400);
DISPLAY INVISIBLE (-275 3400);
FORCEPROP 2 LAST CDS_LIB mstr_standard
J 0
(-450 3325);
PAINT ORANGE (-450 3325);
DISPLAY INVISIBLE (-450 3325);
FORCEPROP 2 LAST ROOM PVCCIN_CPU0_VR
J 0
(-875 3400);
DISPLAY 1.361702 (-875 3400);
PAINT ORANGE (-875 3400);
DISPLAY INVISIBLE (-875 3400);
FORCEPROP 1 LAST OFFPAGE TRUE
J 0
(-125 3200);
DISPLAY 1.170213 (-125 3200);
PAINT GREEN (-125 3200);
DISPLAY INVISIBLE (-125 3200);
FORCEPROP 1 LAST COMMENT_BODY TRUE
J 0
(-495 3230);
DISPLAY 1.170213 (-495 3230);
PAINT GREEN (-495 3230);
DISPLAY INVISIBLE (-495 3230);
FORCEADD OFFPAGE..2
(-1050 2425);
FORCEPROP 2 LAST $XR0 202 
J 0
(-861 2425);
DISPLAY 0.638298 (-861 2425);
PAINT MONO (-861 2425);
FORCEPROP 2 LAST ROOM PVCCIN_CPU0_VR
J 0
(-1475 2500);
DISPLAY 1.361702 (-1475 2500);
PAINT ORANGE (-1475 2500);
DISPLAY INVISIBLE (-1475 2500);
FORCEPROP 2 LAST CDS_LIB mstr_standard
J 0
(-1050 2425);
PAINT ORANGE (-1050 2425);
DISPLAY INVISIBLE (-1050 2425);
FORCEPROP 2 LAST PATH I10
J 0
(-875 2500);
DISPLAY 1.021277 (-875 2500);
PAINT ORANGE (-875 2500);
DISPLAY INVISIBLE (-875 2500);
FORCEPROP 1 LAST OFFPAGE TRUE
J 0
(-725 2300);
DISPLAY 1.170213 (-725 2300);
PAINT GREEN (-725 2300);
DISPLAY INVISIBLE (-725 2300);
FORCEPROP 1 LAST COMMENT_BODY TRUE
J 0
(-1095 2330);
DISPLAY 1.170213 (-1095 2330);
PAINT GREEN (-1095 2330);
DISPLAY INVISIBLE (-1095 2330);
FORCEADD RES..2
(-1100 2000);
FORCEPROP 1 LASTPIN (-1100 1900) $PN 2
J 0
(-1095 1910);
DISPLAY 0.787234 (-1095 1910);
PAINT ORANGE (-1095 1910);
FORCEPROP 1 LAST LOCATION R6P32
J 0
(-1055 2125);
DISPLAY 0.617021 (-1055 2125);
PAINT AQUA (-1055 2125);
FORCEPROP 1 LASTPIN (-1100 2100) $PN 1
J 0
(-1095 2062);
DISPLAY 0.787234 (-1095 2062);
PAINT ORANGE (-1095 2062);
FORCEPROP 1 LAST VALUE 2.0K
J 0
(-1055 2075);
DISPLAY 0.617021 (-1055 2075);
PAINT SKYBLUE (-1055 2075);
FORCEPROP 1 LAST TOLERANCE 1%
J 0
(-1055 2025);
DISPLAY 0.617021 (-1055 2025);
PAINT SKYBLUE (-1055 2025);
FORCEPROP 1 LAST WATTAGE 1/16W
J 0
(-1060 1975);
DISPLAY 0.617021 (-1060 1975);
PAINT SKYBLUE (-1060 1975);
FORCEPROP 1 LAST PACK_TYPE 0402
J 0
(-1060 1825);
DISPLAY 0.617021 (-1060 1825);
PAINT SKYBLUE (-1060 1825);
FORCEPROP 1 LAST MATERIAL EMPTY
J 0
(-1060 1925);
DISPLAY 0.617021 (-1060 1925);
PAINT RED (-1060 1925);
FORCEPROP 1 LAST PART_NUMBER G21796-001
J 0
(-1060 1875);
DISPLAY 0.617021 (-1060 1875);
PAINT BLUE (-1060 1875);
FORCEPROP 2 LAST CDS_LIB mstr_discrete
J 0
(-1100 2000);
PAINT ORANGE (-1100 2000);
DISPLAY INVISIBLE (-1100 2000);
FORCEPROP 2 LAST ROOM PVCCIN_CPU0_VR
J 0
(-1250 2150);
DISPLAY 1.361702 (-1250 2150);
PAINT ORANGE (-1250 2150);
DISPLAY INVISIBLE (-1250 2150);
FORCEPROP 2 LAST CDS_LOCATION R6P32
J 0
(-1055 2125);
DISPLAY 0.617021 (-1055 2125);
PAINT AQUA (-1055 2125);
DISPLAY INVISIBLE (-1055 2125);
FORCEPROP 1 LAST PATH I102
J 0
(-1050 2175);
DISPLAY 0.978723 (-1050 2175);
PAINT WHITE (-1050 2175);
DISPLAY INVISIBLE (-1050 2175);
FORCEPROP 2 LAST SEC 1
J 0
(-1050 2225);
PAINT MONO (-1050 2225);
DISPLAY INVISIBLE (-1050 2225);
FORCEPROP 2 LAST SEC_TYPE 0402
J 0
(-1050 2225);
DISPLAY 1.021277 (-1050 2225);
PAINT ORANGE (-1050 2225);
DISPLAY INVISIBLE (-1050 2225);
FORCEADD RES..2
(-825 2000);
FORCEPROP 1 LAST VALUE 2.0K
J 0
(-780 2075);
DISPLAY 0.617021 (-780 2075);
PAINT SKYBLUE (-780 2075);
FORCEPROP 1 LAST LOCATION R6P37
J 0
(-780 2125);
DISPLAY 0.617021 (-780 2125);
PAINT AQUA (-780 2125);
FORCEPROP 1 LAST TOLERANCE 1%
J 0
(-780 2025);
DISPLAY 0.617021 (-780 2025);
PAINT SKYBLUE (-780 2025);
FORCEPROP 1 LASTPIN (-825 2100) $PN 1
J 0
(-820 2062);
DISPLAY 0.787234 (-820 2062);
PAINT ORANGE (-820 2062);
FORCEPROP 1 LAST MATERIAL EMPTY
J 0
(-785 1925);
DISPLAY 0.617021 (-785 1925);
PAINT RED (-785 1925);
FORCEPROP 1 LAST PART_NUMBER G21796-001
J 0
(-785 1875);
DISPLAY 0.617021 (-785 1875);
PAINT BLUE (-785 1875);
FORCEPROP 1 LAST PACK_TYPE 0402
J 0
(-785 1825);
DISPLAY 0.617021 (-785 1825);
PAINT SKYBLUE (-785 1825);
FORCEPROP 1 LAST WATTAGE 1/16W
J 0
(-785 1975);
DISPLAY 0.617021 (-785 1975);
PAINT SKYBLUE (-785 1975);
FORCEPROP 1 LASTPIN (-825 1900) $PN 2
J 0
(-820 1910);
DISPLAY 0.787234 (-820 1910);
PAINT ORANGE (-820 1910);
FORCEPROP 2 LAST CDS_LIB mstr_discrete
J 0
(-825 2000);
PAINT ORANGE (-825 2000);
DISPLAY INVISIBLE (-825 2000);
FORCEPROP 2 LAST ROOM PVCCIN_CPU0_VR
J 0
(-975 2150);
DISPLAY 1.361702 (-975 2150);
PAINT ORANGE (-975 2150);
DISPLAY INVISIBLE (-975 2150);
FORCEPROP 2 LAST CDS_LOCATION R6P37
J 0
(-780 2125);
DISPLAY 0.617021 (-780 2125);
PAINT AQUA (-780 2125);
DISPLAY INVISIBLE (-780 2125);
FORCEPROP 1 LAST PATH I103
J 0
(-775 2175);
DISPLAY 0.978723 (-775 2175);
PAINT WHITE (-775 2175);
DISPLAY INVISIBLE (-775 2175);
FORCEPROP 2 LAST SEC 1
J 0
(-775 2225);
PAINT MONO (-775 2225);
DISPLAY INVISIBLE (-775 2225);
FORCEPROP 2 LAST SEC_TYPE 0402
J 0
(-775 2225);
DISPLAY 1.021277 (-775 2225);
PAINT ORANGE (-775 2225);
DISPLAY INVISIBLE (-775 2225);
FORCEADD RES..1
(-6675 2525);
FORCEPROP 1 LAST PART_NUMBER G21796-066
J 0
(-6725 2625);
DISPLAY 0.617021 (-6725 2625);
PAINT BLUE (-6725 2625);
FORCEPROP 1 LASTPIN (-6775 2525) $PN 1
J 0
(-6763 2537);
DISPLAY 0.617021 (-6763 2537);
PAINT ORANGE (-6763 2537);
FORCEPROP 2 LAST NO_XNET_CONNECTION 1
J 0
(-6725 2725);
PAINT MONO (-6725 2725);
FORCEPROP 1 LAST PACK_TYPE 0402
J 0
(-6900 2475);
DISPLAY 0.617021 (-6900 2475);
PAINT SKYBLUE (-6900 2475);
FORCEPROP 1 LAST WATTAGE 1/16W
J 2
(-6700 2375);
DISPLAY 0.617021 (-6700 2375);
PAINT SKYBLUE (-6700 2375);
FORCEPROP 1 LASTPIN (-6575 2525) $PN 2
J 0
(-6613 2537);
DISPLAY 0.617021 (-6613 2537);
PAINT ORANGE (-6613 2537);
FORCEPROP 1 LAST MATERIAL CHIP
J 0
(-6675 2375);
DISPLAY 0.617021 (-6675 2375);
PAINT SKYBLUE (-6675 2375);
FORCEPROP 1 LAST TOLERANCE 1%
J 0
(-6675 2425);
DISPLAY 0.617021 (-6675 2425);
PAINT SKYBLUE (-6675 2425);
FORCEPROP 1 LAST VALUE 10.0
J 2
(-6700 2425);
DISPLAY 0.617021 (-6700 2425);
PAINT SKYBLUE (-6700 2425);
FORCEPROP 1 LAST LOCATION R4E8
J 0
(-6725 2575);
DISPLAY 0.617021 (-6725 2575);
PAINT AQUA (-6725 2575);
FORCEPROP 2 LAST CDS_LIB mstr_discrete
J 0
(-6675 2525);
PAINT MONO (-6675 2525);
DISPLAY INVISIBLE (-6675 2525);
FORCEPROP 2 LAST ROOM PVCCIN_CPU0_VR
J 0
(-6725 2675);
DISPLAY 1.021277 (-6725 2675);
PAINT ORANGE (-6725 2675);
DISPLAY INVISIBLE (-6725 2675);
FORCEPROP 1 LAST PATH I109
J 0
(-6725 2675);
DISPLAY 0.978723 (-6725 2675);
PAINT WHITE (-6725 2675);
DISPLAY INVISIBLE (-6725 2675);
FORCEPROP 2 LAST CDS_LOCATION R4E8
J 0
(-6725 2575);
DISPLAY 0.617021 (-6725 2575);
PAINT AQUA (-6725 2575);
DISPLAY INVISIBLE (-6725 2575);
FORCEPROP 2 LAST SEC 1
J 0
(-6725 2725);
DISPLAY 0.680851 (-6725 2725);
PAINT MONO (-6725 2725);
DISPLAY INVISIBLE (-6725 2725);
FORCEPROP 2 LAST SEC_TYPE 0402
J 0
(-6725 2725);
DISPLAY 1.021277 (-6725 2725);
PAINT ORANGE (-6725 2725);
DISPLAY INVISIBLE (-6725 2725);
FORCEADD OFFPAGE..2
(-1050 2325);
FORCEPROP 2 LAST $XR0 203 
J 0
(-861 2325);
DISPLAY 0.638298 (-861 2325);
PAINT MONO (-861 2325);
FORCEPROP 2 LAST ROOM PVCCIN_CPU0_VR
J 0
(-1475 2400);
DISPLAY 1.361702 (-1475 2400);
PAINT ORANGE (-1475 2400);
DISPLAY INVISIBLE (-1475 2400);
FORCEPROP 2 LAST CDS_LIB mstr_standard
J 0
(-1050 2325);
PAINT ORANGE (-1050 2325);
DISPLAY INVISIBLE (-1050 2325);
FORCEPROP 2 LAST PATH I11
J 0
(-875 2400);
DISPLAY 1.021277 (-875 2400);
PAINT ORANGE (-875 2400);
DISPLAY INVISIBLE (-875 2400);
FORCEPROP 1 LAST OFFPAGE TRUE
J 0
(-725 2200);
DISPLAY 1.170213 (-725 2200);
PAINT GREEN (-725 2200);
DISPLAY INVISIBLE (-725 2200);
FORCEPROP 1 LAST COMMENT_BODY TRUE
J 0
(-1095 2230);
DISPLAY 1.170213 (-1095 2230);
PAINT GREEN (-1095 2230);
DISPLAY INVISIBLE (-1095 2230);
FORCEADD RES..1
(-6250 2075);
FORCEPROP 1 LAST PART_NUMBER G21796-066
J 0
(-6300 2175);
DISPLAY 0.617021 (-6300 2175);
PAINT BLUE (-6300 2175);
FORCEPROP 1 LASTPIN (-6350 2075) $PN 1
J 0
(-6338 2087);
DISPLAY 0.617021 (-6338 2087);
PAINT ORANGE (-6338 2087);
FORCEPROP 1 LAST PACK_TYPE 0402
J 0
(-6350 2025);
DISPLAY 0.617021 (-6350 2025);
PAINT SKYBLUE (-6350 2025);
FORCEPROP 1 LAST VALUE 10.0
J 2
(-6275 1975);
DISPLAY 0.617021 (-6275 1975);
PAINT SKYBLUE (-6275 1975);
FORCEPROP 1 LAST TOLERANCE 1%
J 0
(-6250 1975);
DISPLAY 0.617021 (-6250 1975);
PAINT SKYBLUE (-6250 1975);
FORCEPROP 1 LASTPIN (-6150 2075) $PN 2
J 0
(-6188 2087);
DISPLAY 0.617021 (-6188 2087);
PAINT ORANGE (-6188 2087);
FORCEPROP 1 LAST MATERIAL CHIP
J 0
(-6250 1925);
DISPLAY 0.617021 (-6250 1925);
PAINT SKYBLUE (-6250 1925);
FORCEPROP 1 LAST WATTAGE 1/16W
J 2
(-6275 1925);
DISPLAY 0.617021 (-6275 1925);
PAINT SKYBLUE (-6275 1925);
FORCEPROP 1 LAST LOCATION R4D39
J 0
(-6300 2125);
DISPLAY 0.617021 (-6300 2125);
PAINT AQUA (-6300 2125);
FORCEPROP 2 LAST NO_XNET_CONNECTION 1
J 0
(-6425 2125);
PAINT MONO (-6425 2125);
FORCEPROP 2 LAST CDS_LOCATION R4D39
J 0
(-6300 2125);
DISPLAY 0.617021 (-6300 2125);
PAINT AQUA (-6300 2125);
DISPLAY INVISIBLE (-6300 2125);
FORCEPROP 2 LAST SEC 1
J 0
(-6300 2275);
DISPLAY 0.680851 (-6300 2275);
PAINT MONO (-6300 2275);
DISPLAY INVISIBLE (-6300 2275);
FORCEPROP 2 LAST ROOM PVCCIN_CPU0_VR
J 0
(-6300 2225);
DISPLAY 1.021277 (-6300 2225);
PAINT ORANGE (-6300 2225);
DISPLAY INVISIBLE (-6300 2225);
FORCEPROP 1 LAST PATH I110
J 0
(-6300 2225);
DISPLAY 0.978723 (-6300 2225);
PAINT WHITE (-6300 2225);
DISPLAY INVISIBLE (-6300 2225);
FORCEPROP 2 LAST CDS_LIB mstr_discrete
J 0
(-6250 2075);
PAINT MONO (-6250 2075);
DISPLAY INVISIBLE (-6250 2075);
FORCEPROP 2 LAST SEC_TYPE 0402
J 0
(-6300 2275);
DISPLAY 1.021277 (-6300 2275);
PAINT ORANGE (-6300 2275);
DISPLAY INVISIBLE (-6300 2275);
FORCEADD RES..2
R 2
(-3050 4125);
FORCEPROP 1 LASTPIN (-3050 4225) $PN 1
J 2
(-3055 4187);
DISPLAY 0.617021 (-3055 4187);
PAINT ORANGE (-3055 4187);
FORCEPROP 1 LAST PACK_TYPE 0402
J 2
(-3090 3950);
DISPLAY 0.617021 (-3090 3950);
PAINT SKYBLUE (-3090 3950);
FORCEPROP 1 LAST PART_NUMBER G21796-026
J 2
(-3090 4000);
DISPLAY 0.617021 (-3090 4000);
PAINT BLUE (-3090 4000);
FORCEPROP 1 LAST LOCATION R4E3
J 2
(-3095 4250);
DISPLAY 0.617021 (-3095 4250);
PAINT AQUA (-3095 4250);
FORCEPROP 1 LAST VALUE 1.00K
J 2
(-3095 4200);
DISPLAY 0.617021 (-3095 4200);
PAINT SKYBLUE (-3095 4200);
FORCEPROP 1 LAST TOLERANCE 1%
J 2
(-3095 4150);
DISPLAY 0.617021 (-3095 4150);
PAINT SKYBLUE (-3095 4150);
FORCEPROP 1 LAST WATTAGE 1/16W
J 2
(-3090 4100);
DISPLAY 0.617021 (-3090 4100);
PAINT SKYBLUE (-3090 4100);
FORCEPROP 1 LAST MATERIAL CHIP
J 2
(-3090 4050);
DISPLAY 0.617021 (-3090 4050);
PAINT SKYBLUE (-3090 4050);
FORCEPROP 1 LASTPIN (-3050 4025) $PN 2
J 2
(-3055 4035);
DISPLAY 0.617021 (-3055 4035);
PAINT ORANGE (-3055 4035);
FORCEPROP 2 LAST ROOM PVCCIN_CPU0_VR
J 2
(-3100 4300);
DISPLAY 1.361702 (-3100 4300);
PAINT ORANGE (-3100 4300);
DISPLAY INVISIBLE (-3100 4300);
FORCEPROP 1 LAST PATH I111
J 2
(-3100 4300);
DISPLAY 0.978723 (-3100 4300);
PAINT WHITE (-3100 4300);
DISPLAY INVISIBLE (-3100 4300);
FORCEPROP 2 LAST CDS_LOCATION R4E3
J 2
(-3095 4250);
DISPLAY 0.617021 (-3095 4250);
PAINT AQUA (-3095 4250);
DISPLAY INVISIBLE (-3095 4250);
FORCEPROP 2 LAST SEC 1
J 2
(-3100 4350);
DISPLAY 0.680851 (-3100 4350);
PAINT MONO (-3100 4350);
DISPLAY INVISIBLE (-3100 4350);
FORCEPROP 2 LAST SEC_TYPE 0402
J 2
(-3100 4350);
DISPLAY 1.021277 (-3100 4350);
PAINT ORANGE (-3100 4350);
DISPLAY INVISIBLE (-3100 4350);
FORCEPROP 2 LAST CDS_LIB mstr_discrete
J 0
(-3050 4125);
PAINT ORANGE (-3050 4125);
DISPLAY INVISIBLE (-3050 4125);
FORCEADD P3V3_STBY..1
(-4250 4600);
FORCEPROP 3 LASTPIN (-4250 4550) SIG_NAME P3V3_STBY\g
J 0
(-4240 4560);
DISPLAY 0.659574 (-4240 4560);
PAINT MONO (-4240 4560);
DISPLAY INVISIBLE (-4240 4560);
FORCEPROP 1 LAST VOLTAGE 3.3V
J 0
(-4295 4557);
DISPLAY 0.340426 (-4295 4557);
PAINT SKYBLUE (-4295 4557);
DISPLAY INVISIBLE (-4295 4557);
FORCEPROP 1 LAST PATH I112
J 0
(-4205 4602);
DISPLAY 0.340426 (-4205 4602);
PAINT GREEN (-4205 4602);
DISPLAY INVISIBLE (-4205 4602);
FORCEPROP 2 LAST CDS_LIB mstr_symbols
J 0
(-4250 4600);
PAINT ORANGE (-4250 4600);
DISPLAY INVISIBLE (-4250 4600);
FORCEPROP 1 LAST SIZE 1B
J 0
(-4205 4622);
DISPLAY 0.340426 (-4205 4622);
PAINT GREEN (-4205 4622);
DISPLAY INVISIBLE (-4205 4622);
FORCEPROP 1 LAST BODY_TYPE PLUMBING
J 0
(-4295 4557);
DISPLAY 0.340426 (-4295 4557);
PAINT GREEN (-4295 4557);
DISPLAY INVISIBLE (-4295 4557);
FORCEPROP 1 LAST HDL_POWER P3V3_STBY
J 0
(-4550 4475);
DISPLAY 0.872340 (-4550 4475);
PAINT ORANGE (-4550 4475);
DISPLAY INVISIBLE (-4550 4475);
FORCEADD P3V3_STBY..1
(-3050 4550);
FORCEPROP 3 LASTPIN (-3050 4500) SIG_NAME P3V3_STBY\g
J 0
(-3040 4510);
DISPLAY 0.659574 (-3040 4510);
PAINT MONO (-3040 4510);
DISPLAY INVISIBLE (-3040 4510);
FORCEPROP 1 LAST VOLTAGE 3.3V
J 0
(-3095 4507);
DISPLAY 0.340426 (-3095 4507);
PAINT SKYBLUE (-3095 4507);
DISPLAY INVISIBLE (-3095 4507);
FORCEPROP 1 LAST PATH I113
J 0
(-3005 4552);
DISPLAY 0.340426 (-3005 4552);
PAINT GREEN (-3005 4552);
DISPLAY INVISIBLE (-3005 4552);
FORCEPROP 2 LAST CDS_LIB mstr_symbols
J 0
(-3050 4550);
PAINT ORANGE (-3050 4550);
DISPLAY INVISIBLE (-3050 4550);
FORCEPROP 1 LAST SIZE 1B
J 0
(-3005 4572);
DISPLAY 0.340426 (-3005 4572);
PAINT GREEN (-3005 4572);
DISPLAY INVISIBLE (-3005 4572);
FORCEPROP 1 LAST BODY_TYPE PLUMBING
J 0
(-3095 4507);
DISPLAY 0.340426 (-3095 4507);
PAINT GREEN (-3095 4507);
DISPLAY INVISIBLE (-3095 4507);
FORCEPROP 1 LAST HDL_POWER P3V3_STBY
J 0
(-3350 4425);
DISPLAY 0.872340 (-3350 4425);
PAINT ORANGE (-3350 4425);
DISPLAY INVISIBLE (-3350 4425);
FORCEADD P3V3_STBY..1
(-375 2325);
FORCEPROP 3 LASTPIN (-375 2275) SIG_NAME P3V3_STBY\g
J 0
(-365 2285);
DISPLAY 0.659574 (-365 2285);
PAINT MONO (-365 2285);
DISPLAY INVISIBLE (-365 2285);
FORCEPROP 1 LAST PATH I115
J 0
(-330 2327);
DISPLAY 0.340426 (-330 2327);
PAINT GREEN (-330 2327);
DISPLAY INVISIBLE (-330 2327);
FORCEPROP 1 LAST SIZE 1B
J 0
(-330 2347);
DISPLAY 0.340426 (-330 2347);
PAINT GREEN (-330 2347);
DISPLAY INVISIBLE (-330 2347);
FORCEPROP 2 LAST CDS_LIB mstr_symbols
J 0
(-375 2325);
PAINT ORANGE (-375 2325);
DISPLAY INVISIBLE (-375 2325);
FORCEPROP 1 LAST VOLTAGE 3.3V
J 0
(-420 2282);
DISPLAY 0.340426 (-420 2282);
PAINT SKYBLUE (-420 2282);
DISPLAY INVISIBLE (-420 2282);
FORCEPROP 1 LAST BODY_TYPE PLUMBING
J 0
(-420 2282);
DISPLAY 0.340426 (-420 2282);
PAINT GREEN (-420 2282);
DISPLAY INVISIBLE (-420 2282);
FORCEPROP 1 LAST HDL_POWER P3V3_STBY
J 0
(-675 2200);
DISPLAY 0.872340 (-675 2200);
PAINT ORANGE (-675 2200);
DISPLAY INVISIBLE (-675 2200);
FORCEADD RES..2
(-1575 4200);
FORCEPROP 1 LAST PART_NUMBER G21796-311
J 0
(-1535 4075);
DISPLAY 0.617021 (-1535 4075);
PAINT BLUE (-1535 4075);
FORCEPROP 1 LAST TOLERANCE 1.0%
J 0
(-1530 4225);
DISPLAY 0.617021 (-1530 4225);
PAINT SKYBLUE (-1530 4225);
FORCEPROP 1 LAST PACK_TYPE 0402
J 0
(-1535 4025);
DISPLAY 0.617021 (-1535 4025);
PAINT SKYBLUE (-1535 4025);
FORCEPROP 1 LASTPIN (-1575 4100) $PN 2
J 0
(-1570 4110);
DISPLAY 0.617021 (-1570 4110);
PAINT ORANGE (-1570 4110);
FORCEPROP 1 LAST LOCATION R4E20
J 0
(-1530 4325);
DISPLAY 0.617021 (-1530 4325);
PAINT AQUA (-1530 4325);
FORCEPROP 1 LASTPIN (-1575 4300) $PN 1
J 0
(-1570 4262);
DISPLAY 0.617021 (-1570 4262);
PAINT ORANGE (-1570 4262);
FORCEPROP 1 LAST MATERIAL EMPTY
R 1
J 0
(-1385 4125);
DISPLAY 0.617021 (-1385 4125);
PAINT RED (-1385 4125);
FORCEPROP 1 LAST VALUE 2.26K
J 0
(-1530 4275);
DISPLAY 0.617021 (-1530 4275);
PAINT SKYBLUE (-1530 4275);
FORCEPROP 1 LAST WATTAGE 1/16W
J 0
(-1535 4175);
DISPLAY 0.617021 (-1535 4175);
PAINT SKYBLUE (-1535 4175);
FORCEPROP 2 LAST CDS_LIB mstr_discrete
J 0
(-1575 4200);
PAINT ORANGE (-1575 4200);
DISPLAY INVISIBLE (-1575 4200);
FORCEPROP 2 LAST ROOM PVCCIN_CPU0_VR
J 0
(-1725 4350);
DISPLAY 1.361702 (-1725 4350);
PAINT ORANGE (-1725 4350);
DISPLAY INVISIBLE (-1725 4350);
FORCEPROP 1 LAST PATH I116
J 0
(-1525 4375);
DISPLAY 0.978723 (-1525 4375);
PAINT WHITE (-1525 4375);
DISPLAY INVISIBLE (-1525 4375);
FORCEPROP 2 LAST SEC 1
J 0
(-1525 4425);
DISPLAY 0.680851 (-1525 4425);
PAINT MONO (-1525 4425);
DISPLAY INVISIBLE (-1525 4425);
FORCEPROP 2 LAST SEC_TYPE 0402
J 0
(-1525 4425);
DISPLAY 1.021277 (-1525 4425);
PAINT ORANGE (-1525 4425);
DISPLAY INVISIBLE (-1525 4425);
FORCEADD OFFPAGE..2
(-1050 3075);
FORCEPROP 2 LAST $XR0 95 
J 0
(-861 3075);
DISPLAY 0.638298 (-861 3075);
PAINT MONO (-861 3075);
FORCEPROP 2 LAST ROOM PVCCIN_CPU0_VR
J 0
(-1475 3150);
DISPLAY 1.361702 (-1475 3150);
PAINT ORANGE (-1475 3150);
DISPLAY INVISIBLE (-1475 3150);
FORCEPROP 2 LAST CDS_LIB mstr_standard
J 0
(-1050 3075);
PAINT ORANGE (-1050 3075);
DISPLAY INVISIBLE (-1050 3075);
FORCEPROP 2 LAST PATH I118
J 0
(-875 3150);
DISPLAY 1.021277 (-875 3150);
PAINT ORANGE (-875 3150);
DISPLAY INVISIBLE (-875 3150);
FORCEPROP 1 LAST OFFPAGE TRUE
J 0
(-725 2950);
DISPLAY 1.170213 (-725 2950);
PAINT GREEN (-725 2950);
DISPLAY INVISIBLE (-725 2950);
FORCEPROP 1 LAST COMMENT_BODY TRUE
J 0
(-1095 2980);
DISPLAY 1.170213 (-1095 2980);
PAINT GREEN (-1095 2980);
DISPLAY INVISIBLE (-1095 2980);
FORCEADD OFFPAGE..2
(-1050 2275);
FORCEPROP 2 LAST $XR0 204 
J 0
(-861 2275);
DISPLAY 0.638298 (-861 2275);
PAINT MONO (-861 2275);
FORCEPROP 2 LAST ROOM PVCCIN_CPU0_VR
J 0
(-1475 2350);
DISPLAY 1.361702 (-1475 2350);
PAINT ORANGE (-1475 2350);
DISPLAY INVISIBLE (-1475 2350);
FORCEPROP 2 LAST CDS_LIB mstr_standard
J 0
(-1050 2275);
PAINT ORANGE (-1050 2275);
DISPLAY INVISIBLE (-1050 2275);
FORCEPROP 2 LAST PATH I12
J 0
(-875 2350);
DISPLAY 1.021277 (-875 2350);
PAINT ORANGE (-875 2350);
DISPLAY INVISIBLE (-875 2350);
FORCEPROP 1 LAST OFFPAGE TRUE
J 0
(-725 2150);
DISPLAY 1.170213 (-725 2150);
PAINT GREEN (-725 2150);
DISPLAY INVISIBLE (-725 2150);
FORCEPROP 1 LAST COMMENT_BODY TRUE
J 0
(-1095 2180);
DISPLAY 1.170213 (-1095 2180);
PAINT GREEN (-1095 2180);
DISPLAY INVISIBLE (-1095 2180);
FORCEADD RES..2
(-4400 900);
FORCEPROP 1 LAST VALUE 4.02K
J 0
(-4355 975);
DISPLAY 0.617021 (-4355 975);
PAINT SKYBLUE (-4355 975);
FORCEPROP 1 LAST TOLERANCE 1%
J 0
(-4355 925);
DISPLAY 0.617021 (-4355 925);
PAINT SKYBLUE (-4355 925);
FORCEPROP 1 LASTPIN (-4400 1000) $PN 1
J 0
(-4395 962);
DISPLAY 0.617021 (-4395 962);
PAINT ORANGE (-4395 962);
FORCEPROP 1 LAST MATERIAL CHIP
J 0
(-4360 825);
DISPLAY 0.617021 (-4360 825);
PAINT SKYBLUE (-4360 825);
FORCEPROP 1 LAST PART_NUMBER G21796-082
J 0
(-4360 775);
DISPLAY 0.617021 (-4360 775);
PAINT BLUE (-4360 775);
FORCEPROP 1 LASTPIN (-4400 800) $PN 2
J 0
(-4395 810);
DISPLAY 0.617021 (-4395 810);
PAINT ORANGE (-4395 810);
FORCEPROP 1 LAST WATTAGE 1/16W
J 0
(-4360 875);
DISPLAY 0.617021 (-4360 875);
PAINT SKYBLUE (-4360 875);
FORCEPROP 1 LAST LOCATION R6P27
J 0
(-4355 1025);
DISPLAY 0.617021 (-4355 1025);
PAINT AQUA (-4355 1025);
FORCEPROP 1 LAST PACK_TYPE 0402
J 0
(-4360 725);
DISPLAY 0.617021 (-4360 725);
PAINT SKYBLUE (-4360 725);
FORCEPROP 2 LAST CDS_LIB mstr_discrete
J 0
(-4400 900);
PAINT ORANGE (-4400 900);
DISPLAY INVISIBLE (-4400 900);
FORCEPROP 0 LAST ROOM PVCCIN_CPU0_VR
J 0
(-4350 1125);
DISPLAY 1.021277 (-4350 1125);
PAINT ORANGE (-4350 1125);
DISPLAY INVISIBLE (-4350 1125);
FORCEPROP 2 LAST CDS_LOCATION R6P27
J 0
(-4355 1025);
DISPLAY 0.617021 (-4355 1025);
PAINT AQUA (-4355 1025);
DISPLAY INVISIBLE (-4355 1025);
FORCEPROP 2 LAST SEC 1
J 0
(-4350 1125);
PAINT MONO (-4350 1125);
DISPLAY INVISIBLE (-4350 1125);
FORCEPROP 2 LAST SEC_TYPE 0402
J 0
(-4350 1125);
DISPLAY 1.021277 (-4350 1125);
PAINT ORANGE (-4350 1125);
DISPLAY INVISIBLE (-4350 1125);
FORCEPROP 1 LAST PATH I120
J 0
(-4350 1075);
DISPLAY 0.978723 (-4350 1075);
PAINT WHITE (-4350 1075);
DISPLAY INVISIBLE (-4350 1075);
FORCEADD RES..2
(-4725 900);
FORCEPROP 1 LAST WATTAGE 1/16W
J 0
(-4685 875);
DISPLAY 0.617021 (-4685 875);
PAINT SKYBLUE (-4685 875);
FORCEPROP 1 LAST TOLERANCE 1%
J 0
(-4680 925);
DISPLAY 0.617021 (-4680 925);
PAINT SKYBLUE (-4680 925);
FORCEPROP 1 LAST PART_NUMBER G21796-082
J 0
(-4685 775);
DISPLAY 0.617021 (-4685 775);
PAINT BLUE (-4685 775);
FORCEPROP 1 LAST MATERIAL CHIP
J 0
(-4685 825);
DISPLAY 0.617021 (-4685 825);
PAINT SKYBLUE (-4685 825);
FORCEPROP 1 LAST LOCATION R6P28
J 0
(-4680 1025);
DISPLAY 0.617021 (-4680 1025);
PAINT AQUA (-4680 1025);
FORCEPROP 1 LASTPIN (-4725 800) $PN 2
J 0
(-4720 810);
DISPLAY 0.617021 (-4720 810);
PAINT ORANGE (-4720 810);
FORCEPROP 1 LASTPIN (-4725 1000) $PN 1
J 0
(-4720 962);
DISPLAY 0.617021 (-4720 962);
PAINT ORANGE (-4720 962);
FORCEPROP 1 LAST VALUE 4.02K
J 0
(-4680 975);
DISPLAY 0.617021 (-4680 975);
PAINT SKYBLUE (-4680 975);
FORCEPROP 1 LAST PACK_TYPE 0402
J 0
(-4685 725);
DISPLAY 0.617021 (-4685 725);
PAINT SKYBLUE (-4685 725);
FORCEPROP 2 LAST CDS_LIB mstr_discrete
J 0
(-4725 900);
PAINT ORANGE (-4725 900);
DISPLAY INVISIBLE (-4725 900);
FORCEPROP 2 LAST SEC_TYPE 0402
J 0
(-4675 1125);
DISPLAY 1.021277 (-4675 1125);
PAINT ORANGE (-4675 1125);
DISPLAY INVISIBLE (-4675 1125);
FORCEPROP 2 LAST SEC 1
J 0
(-4675 1125);
PAINT MONO (-4675 1125);
DISPLAY INVISIBLE (-4675 1125);
FORCEPROP 2 LAST CDS_LOCATION R6P28
J 0
(-4680 1025);
DISPLAY 0.617021 (-4680 1025);
PAINT AQUA (-4680 1025);
DISPLAY INVISIBLE (-4680 1025);
FORCEPROP 1 LAST PATH I121
J 0
(-4675 1075);
DISPLAY 0.978723 (-4675 1075);
PAINT WHITE (-4675 1075);
DISPLAY INVISIBLE (-4675 1075);
FORCEPROP 0 LAST ROOM PVCCIN_CPU0_VR
J 0
(-4675 1125);
DISPLAY 1.021277 (-4675 1125);
PAINT ORANGE (-4675 1125);
DISPLAY INVISIBLE (-4675 1125);
FORCEADD GND..1
(-2900 775);
FORCEPROP 3 LASTPIN (-2900 825) SIG_NAME GND\g
J 0
(-2890 835);
DISPLAY 0.659574 (-2890 835);
PAINT MONO (-2890 835);
DISPLAY INVISIBLE (-2890 835);
FORCEPROP 1 LAST SIZE 1B
J 0
(-2825 725);
DISPLAY 1.468085 (-2825 725);
PAINT GREEN (-2825 725);
DISPLAY INVISIBLE (-2825 725);
FORCEPROP 2 LAST CDS_LIB mstr_symbols
J 0
(-2900 775);
PAINT MONO (-2900 775);
DISPLAY INVISIBLE (-2900 775);
FORCEPROP 1 LAST PATH I123
J 0
(-2825 775);
DISPLAY 0.872340 (-2825 775);
PAINT AQUA (-2825 775);
DISPLAY INVISIBLE (-2825 775);
FORCEPROP 1 LAST VOLTAGE 0
J 0
(-2900 775);
PAINT SKYBLUE (-2900 775);
DISPLAY INVISIBLE (-2900 775);
FORCEPROP 1 LAST BODY_TYPE PLUMBING
J 0
(-2945 732);
DISPLAY 0.340426 (-2945 732);
PAINT GREEN (-2945 732);
DISPLAY INVISIBLE (-2945 732);
FORCEPROP 1 LAST HDL_POWER GND
J 0
(-2900 925);
DISPLAY 1.468085 (-2900 925);
PAINT GREEN (-2900 925);
DISPLAY INVISIBLE (-2900 925);
FORCEADD RES..1
(-1125 3325);
FORCEPROP 1 LASTPIN (-1225 3325) $PN 1
J 0
(-1213 3337);
DISPLAY 0.787234 (-1213 3337);
PAINT ORANGE (-1213 3337);
FORCEPROP 1 LAST WATTAGE 1/16W
J 2
(-1150 3175);
DISPLAY 0.617021 (-1150 3175);
PAINT SKYBLUE (-1150 3175);
FORCEPROP 1 LAST PART_NUMBER G21796-250
J 0
(-1175 3425);
DISPLAY 0.617021 (-1175 3425);
PAINT BLUE (-1175 3425);
FORCEPROP 1 LAST LOCATION R4D63
J 0
(-1175 3375);
DISPLAY 0.617021 (-1175 3375);
PAINT AQUA (-1175 3375);
FORCEPROP 1 LAST VALUE 22.1
J 2
(-1150 3225);
DISPLAY 0.617021 (-1150 3225);
PAINT SKYBLUE (-1150 3225);
FORCEPROP 1 LASTPIN (-1025 3325) $PN 2
J 0
(-1063 3337);
DISPLAY 0.787234 (-1063 3337);
PAINT ORANGE (-1063 3337);
FORCEPROP 1 LAST PACK_TYPE 0402
J 0
(-1000 3250);
DISPLAY 0.617021 (-1000 3250);
PAINT SKYBLUE (-1000 3250);
FORCEPROP 1 LAST TOLERANCE 1.0%
J 0
(-1125 3225);
DISPLAY 0.617021 (-1125 3225);
PAINT SKYBLUE (-1125 3225);
FORCEPROP 1 LAST MATERIAL CHIP
J 0
(-1125 3175);
DISPLAY 0.617021 (-1125 3175);
PAINT SKYBLUE (-1125 3175);
FORCEPROP 2 LAST CDS_LIB mstr_discrete
J 0
(-1125 3325);
PAINT MONO (-1125 3325);
DISPLAY INVISIBLE (-1125 3325);
FORCEPROP 2 LAST ROOM PVCCIN_CPU0_VR
J 0
(-1025 3425);
DISPLAY 1.361702 (-1025 3425);
PAINT ORANGE (-1025 3425);
DISPLAY INVISIBLE (-1025 3425);
FORCEPROP 1 LAST PATH I124
J 0
(-1175 3475);
DISPLAY 0.978723 (-1175 3475);
PAINT WHITE (-1175 3475);
DISPLAY INVISIBLE (-1175 3475);
FORCEPROP 2 LAST CDS_LOCATION R4D63
J 0
(-1175 3375);
DISPLAY 0.617021 (-1175 3375);
PAINT AQUA (-1175 3375);
DISPLAY INVISIBLE (-1175 3375);
FORCEPROP 2 LAST SEC 1
J 0
(-1175 3525);
PAINT MONO (-1175 3525);
DISPLAY INVISIBLE (-1175 3525);
FORCEPROP 2 LAST SEC_TYPE 0402
J 0
(-1175 3525);
DISPLAY 1.021277 (-1175 3525);
PAINT ORANGE (-1175 3525);
DISPLAY INVISIBLE (-1175 3525);
FORCEADD CAP..1
(-1450 2075);
FORCEPROP 1 LAST VOLTAGE 50V
J 0
(-1400 2075);
DISPLAY 0.617021 (-1400 2075);
PAINT SKYBLUE (-1400 2075);
FORCEPROP 1 LASTPIN (-1450 1975) $PN 2
J 0
(-1440 1955);
DISPLAY 0.617021 (-1440 1955);
PAINT ORANGE (-1440 1955);
FORCEPROP 1 LASTPIN (-1450 2175) $PN 1
J 0
(-1440 2155);
DISPLAY 0.617021 (-1440 2155);
PAINT ORANGE (-1440 2155);
FORCEPROP 1 LAST LOCATION C4D42
J 0
(-1400 2175);
DISPLAY 0.617021 (-1400 2175);
PAINT AQUA (-1400 2175);
FORCEPROP 1 LAST VALUE 1000PF
J 0
(-1400 2125);
DISPLAY 0.617021 (-1400 2125);
PAINT SKYBLUE (-1400 2125);
FORCEPROP 1 LAST TOLERANCE 10%
J 0
(-1400 2025);
DISPLAY 0.617021 (-1400 2025);
PAINT SKYBLUE (-1400 2025);
FORCEPROP 1 LAST MATERIAL X7R
J 0
(-1400 1975);
DISPLAY 0.617021 (-1400 1975);
PAINT SKYBLUE (-1400 1975);
FORCEPROP 1 LAST PACK_TYPE 0402LF
J 0
(-1400 1875);
DISPLAY 0.617021 (-1400 1875);
PAINT SKYBLUE (-1400 1875);
FORCEPROP 1 LAST PART_NUMBER A36096-046
J 0
(-1400 1925);
DISPLAY 0.617021 (-1400 1925);
PAINT BLUE (-1400 1925);
FORCEPROP 2 LAST CDS_LIB mstr_discrete
J 0
(-1450 2075);
PAINT MONO (-1450 2075);
DISPLAY INVISIBLE (-1450 2075);
FORCEPROP 2 LAST SEC 1
J 0
(-1400 2275);
DISPLAY 0.680851 (-1400 2275);
PAINT MONO (-1400 2275);
DISPLAY INVISIBLE (-1400 2275);
FORCEPROP 2 LAST CDS_LOCATION C4D42
J 0
(-1400 2175);
DISPLAY 0.617021 (-1400 2175);
PAINT AQUA (-1400 2175);
DISPLAY INVISIBLE (-1400 2175);
FORCEPROP 1 LAST PATH I125
J 0
(-1400 2225);
DISPLAY 0.978723 (-1400 2225);
PAINT WHITE (-1400 2225);
DISPLAY INVISIBLE (-1400 2225);
FORCEPROP 2 LAST SEC_TYPE 0402LF
J 0
(-1400 2275);
DISPLAY 1.021277 (-1400 2275);
PAINT ORANGE (-1400 2275);
DISPLAY INVISIBLE (-1400 2275);
FORCEPROP 0 LAST ROOM PVCCIN_CPU0_VR
J 0
(-1400 2275);
DISPLAY 1.021277 (-1400 2275);
PAINT ORANGE (-1400 2275);
DISPLAY INVISIBLE (-1400 2275);
FORCEADD GND..1
(-1450 1850);
FORCEPROP 3 LASTPIN (-1450 1900) SIG_NAME GND\g
J 0
(-1440 1910);
DISPLAY 0.659574 (-1440 1910);
PAINT MONO (-1440 1910);
DISPLAY INVISIBLE (-1440 1910);
FORCEPROP 2 LAST ROOM PVCCIN_CPU0_VR
J 0
(-2025 1925);
DISPLAY 1.361702 (-2025 1925);
PAINT ORANGE (-2025 1925);
DISPLAY INVISIBLE (-2025 1925);
FORCEPROP 2 LAST CDS_LIB mstr_symbols
J 0
(-1450 1850);
PAINT MONO (-1450 1850);
DISPLAY INVISIBLE (-1450 1850);
FORCEPROP 1 LAST VOLTAGE 0
J 0
(-1450 1850);
PAINT SKYBLUE (-1450 1850);
DISPLAY INVISIBLE (-1450 1850);
FORCEPROP 1 LAST PATH I126
J 0
(-1375 1850);
DISPLAY 0.872340 (-1375 1850);
PAINT AQUA (-1375 1850);
DISPLAY INVISIBLE (-1375 1850);
FORCEPROP 1 LAST SIZE 1B
J 0
(-1375 1800);
DISPLAY 1.170213 (-1375 1800);
PAINT AQUA (-1375 1800);
DISPLAY INVISIBLE (-1375 1800);
FORCEPROP 1 LAST BODY_TYPE PLUMBING
J 0
(-1495 1807);
DISPLAY 0.340426 (-1495 1807);
PAINT GREEN (-1495 1807);
DISPLAY INVISIBLE (-1495 1807);
FORCEPROP 1 LAST HDL_POWER GND
J 0
(-1450 2000);
DISPLAY 1.170213 (-1450 2000);
PAINT GREEN (-1450 2000);
DISPLAY INVISIBLE (-1450 2000);
FORCEADD RES..1
(-1800 2675);
FORCEPROP 1 LASTPIN (-1900 2675) $PN 1
J 0
(-1888 2687);
DISPLAY 0.617021 (-1888 2687);
PAINT ORANGE (-1888 2687);
FORCEPROP 1 LASTPIN (-1700 2675) $PN 2
J 0
(-1738 2687);
DISPLAY 0.617021 (-1738 2687);
PAINT ORANGE (-1738 2687);
FORCEPROP 1 LAST TOLERANCE 1%
J 0
(-1800 2575);
DISPLAY 0.617021 (-1800 2575);
PAINT SKYBLUE (-1800 2575);
FORCEPROP 1 LAST MATERIAL CHIP
J 0
(-1600 2575);
DISPLAY 0.617021 (-1600 2575);
PAINT SKYBLUE (-1600 2575);
FORCEPROP 1 LAST PACK_TYPE 0402
J 0
(-1700 2575);
DISPLAY 0.617021 (-1700 2575);
PAINT SKYBLUE (-1700 2575);
FORCEPROP 1 LAST VALUE 33.2
J 2
(-1825 2575);
DISPLAY 0.617021 (-1825 2575);
PAINT SKYBLUE (-1825 2575);
FORCEPROP 1 LAST LOCATION R4D65
J 0
(-1675 2625);
DISPLAY 0.617021 (-1675 2625);
PAINT AQUA (-1675 2625);
FORCEPROP 1 LAST PART_NUMBER G21796-074
J 0
(-1975 2625);
DISPLAY 0.617021 (-1975 2625);
PAINT BLUE (-1975 2625);
FORCEPROP 1 LAST WATTAGE 1/16W
J 2
(-1950 2575);
DISPLAY 0.617021 (-1950 2575);
PAINT SKYBLUE (-1950 2575);
FORCEPROP 2 LAST CDS_LOCATION R4D65
J 0
(-1900 2725);
DISPLAY 0.617021 (-1900 2725);
PAINT AQUA (-1900 2725);
DISPLAY INVISIBLE (-1900 2725);
FORCEPROP 2 LAST CDS_LIB mstr_discrete
J 0
(-1800 2675);
PAINT MONO (-1800 2675);
DISPLAY INVISIBLE (-1800 2675);
FORCEPROP 1 LAST PATH I127
J 0
(-1850 2825);
DISPLAY 0.978723 (-1850 2825);
PAINT WHITE (-1850 2825);
DISPLAY INVISIBLE (-1850 2825);
FORCEPROP 2 LAST SEC 1
J 0
(-1850 2875);
DISPLAY 0.680851 (-1850 2875);
PAINT MONO (-1850 2875);
DISPLAY INVISIBLE (-1850 2875);
FORCEPROP 2 LAST SEC_TYPE 0402
J 0
(-1850 2875);
DISPLAY 1.021277 (-1850 2875);
PAINT ORANGE (-1850 2875);
DISPLAY INVISIBLE (-1850 2875);
FORCEADD RES..1
(-2400 2975);
FORCEPROP 1 LAST MATERIAL CHIP
J 0
(-2400 2825);
DISPLAY 0.617021 (-2400 2825);
PAINT SKYBLUE (-2400 2825);
FORCEPROP 1 LAST TOLERANCE 1%
J 0
(-2400 2875);
DISPLAY 0.617021 (-2400 2875);
PAINT SKYBLUE (-2400 2875);
FORCEPROP 1 LAST PART_NUMBER G21796-074
J 0
(-2450 3075);
DISPLAY 0.617021 (-2450 3075);
PAINT BLUE (-2450 3075);
FORCEPROP 1 LAST VALUE 33.2
J 2
(-2425 2875);
DISPLAY 0.617021 (-2425 2875);
PAINT SKYBLUE (-2425 2875);
FORCEPROP 1 LAST WATTAGE 1/16W
J 2
(-2425 2825);
DISPLAY 0.617021 (-2425 2825);
PAINT SKYBLUE (-2425 2825);
FORCEPROP 1 LASTPIN (-2500 2975) $PN 1
J 0
(-2488 2987);
DISPLAY 0.617021 (-2488 2987);
PAINT ORANGE (-2488 2987);
FORCEPROP 1 LAST LOCATION R6P45
J 0
(-2450 3025);
DISPLAY 0.617021 (-2450 3025);
PAINT AQUA (-2450 3025);
FORCEPROP 1 LASTPIN (-2300 2975) $PN 2
J 0
(-2338 2987);
DISPLAY 0.617021 (-2338 2987);
PAINT ORANGE (-2338 2987);
FORCEPROP 1 LAST PACK_TYPE 0402
J 0
(-2325 2900);
DISPLAY 0.617021 (-2325 2900);
PAINT SKYBLUE (-2325 2900);
FORCEPROP 2 LAST CDS_LOCATION R6P45
J 0
(-2450 3025);
DISPLAY 0.617021 (-2450 3025);
PAINT AQUA (-2450 3025);
DISPLAY INVISIBLE (-2450 3025);
FORCEPROP 2 LAST CDS_LIB mstr_discrete
J 0
(-2400 2975);
PAINT MONO (-2400 2975);
DISPLAY INVISIBLE (-2400 2975);
FORCEPROP 1 LAST PATH I128
J 0
(-2450 3125);
DISPLAY 0.978723 (-2450 3125);
PAINT WHITE (-2450 3125);
DISPLAY INVISIBLE (-2450 3125);
FORCEPROP 2 LAST SEC 1
J 0
(-2450 3175);
DISPLAY 0.680851 (-2450 3175);
PAINT MONO (-2450 3175);
DISPLAY INVISIBLE (-2450 3175);
FORCEPROP 2 LAST SEC_TYPE 0402
J 0
(-2450 3175);
DISPLAY 1.021277 (-2450 3175);
PAINT ORANGE (-2450 3175);
DISPLAY INVISIBLE (-2450 3175);
FORCEADD RES..1
(-5100 2225);
FORCEPROP 1 LAST VALUE 0.0
J 2
(-5200 2125);
DISPLAY 0.617021 (-5200 2125);
PAINT SKYBLUE (-5200 2125);
FORCEPROP 1 LAST LOCATION R6P18
J 0
(-5150 2275);
DISPLAY 0.617021 (-5150 2275);
PAINT AQUA (-5150 2275);
FORCEPROP 1 LASTPIN (-5000 2225) $PN 2
J 0
(-5038 2237);
DISPLAY 0.617021 (-5038 2237);
PAINT ORANGE (-5038 2237);
FORCEPROP 1 LAST TOLERANCE 5%
J 0
(-5150 2125);
DISPLAY 0.617021 (-5150 2125);
PAINT SKYBLUE (-5150 2125);
FORCEPROP 1 LAST WATTAGE 1/16W
J 2
(-5125 2075);
DISPLAY 0.617021 (-5125 2075);
PAINT SKYBLUE (-5125 2075);
FORCEPROP 1 LASTPIN (-5200 2225) $PN 1
J 0
(-5188 2237);
DISPLAY 0.617021 (-5188 2237);
PAINT ORANGE (-5188 2237);
FORCEPROP 1 LAST PART_NUMBER G21497-005
J 0
(-5250 2175);
DISPLAY 0.617021 (-5250 2175);
PAINT BLUE (-5250 2175);
FORCEPROP 1 LAST PACK_TYPE 0402
J 0
(-5025 2125);
DISPLAY 0.617021 (-5025 2125);
PAINT SKYBLUE (-5025 2125);
FORCEPROP 1 LAST MATERIAL CHIP
J 0
(-5100 2075);
DISPLAY 0.617021 (-5100 2075);
PAINT SKYBLUE (-5100 2075);
FORCEPROP 2 LAST CDS_LOCATION R6P18
J 0
(-5150 2275);
DISPLAY 0.617021 (-5150 2275);
PAINT AQUA (-5150 2275);
DISPLAY INVISIBLE (-5150 2275);
FORCEPROP 2 LAST SEC_TYPE 0402
J 0
(-5150 2425);
DISPLAY 1.021277 (-5150 2425);
PAINT ORANGE (-5150 2425);
DISPLAY INVISIBLE (-5150 2425);
FORCEPROP 2 LAST SEC 1
J 0
(-5150 2425);
PAINT MONO (-5150 2425);
DISPLAY INVISIBLE (-5150 2425);
FORCEPROP 1 LAST PATH I131
J 0
(-5150 2375);
DISPLAY 0.978723 (-5150 2375);
PAINT WHITE (-5150 2375);
DISPLAY INVISIBLE (-5150 2375);
FORCEPROP 2 LAST ROOM PVCCIN_CPU0_VR
J 0
(-5150 2325);
DISPLAY 1.361702 (-5150 2325);
PAINT ORANGE (-5150 2325);
DISPLAY INVISIBLE (-5150 2325);
FORCEPROP 2 LAST CDS_LIB mstr_discrete
J 0
(-5100 2225);
PAINT ORANGE (-5100 2225);
DISPLAY INVISIBLE (-5100 2225);
FORCEADD RES..2
(-4775 4350);
FORCEPROP 1 LAST PART_NUMBER G21796-026
J 0
(-4735 4225);
DISPLAY 0.617021 (-4735 4225);
PAINT BLUE (-4735 4225);
FORCEPROP 1 LAST PACK_TYPE 0402
J 0
(-4735 4175);
DISPLAY 0.617021 (-4735 4175);
PAINT SKYBLUE (-4735 4175);
FORCEPROP 1 LAST TOLERANCE 1%
J 0
(-4730 4375);
DISPLAY 0.617021 (-4730 4375);
PAINT SKYBLUE (-4730 4375);
FORCEPROP 1 LAST VALUE 1.00K
J 0
(-4730 4425);
DISPLAY 0.617021 (-4730 4425);
PAINT SKYBLUE (-4730 4425);
FORCEPROP 1 LAST MATERIAL CHIP
J 0
(-4735 4275);
DISPLAY 0.617021 (-4735 4275);
PAINT SKYBLUE (-4735 4275);
FORCEPROP 1 LAST WATTAGE 1/16W
J 0
(-4735 4325);
DISPLAY 0.617021 (-4735 4325);
PAINT SKYBLUE (-4735 4325);
FORCEPROP 1 LASTPIN (-4775 4450) $PN 1
J 0
(-4770 4412);
DISPLAY 0.787234 (-4770 4412);
PAINT ORANGE (-4770 4412);
FORCEPROP 1 LASTPIN (-4775 4250) $PN 2
J 0
(-4770 4260);
DISPLAY 0.787234 (-4770 4260);
PAINT ORANGE (-4770 4260);
FORCEPROP 1 LAST LOCATION R6P16
J 0
(-4730 4475);
DISPLAY 0.617021 (-4730 4475);
PAINT AQUA (-4730 4475);
FORCEPROP 2 LAST CDS_LIB mstr_discrete
J 0
(-4775 4350);
PAINT ORANGE (-4775 4350);
DISPLAY INVISIBLE (-4775 4350);
FORCEPROP 0 LAST ROOM BMC
J 0
(-4725 4575);
DISPLAY 0.617021 (-4725 4575);
PAINT ORANGE (-4725 4575);
DISPLAY INVISIBLE (-4725 4575);
FORCEPROP 1 LAST PATH I132
J 0
(-4725 4525);
DISPLAY 0.978723 (-4725 4525);
PAINT WHITE (-4725 4525);
DISPLAY INVISIBLE (-4725 4525);
FORCEPROP 2 LAST CDS_LOCATION R6P16
J 0
(-4730 4475);
DISPLAY 0.617021 (-4730 4475);
PAINT AQUA (-4730 4475);
DISPLAY INVISIBLE (-4730 4475);
FORCEPROP 0 LAST BOM_COST SM_CONTROLLER
J 0
(-4725 4675);
DISPLAY 1.021277 (-4725 4675);
PAINT ORANGE (-4725 4675);
DISPLAY INVISIBLE (-4725 4675);
FORCEPROP 2 LAST SEC 1
J 0
(-4725 4575);
PAINT MONO (-4725 4575);
DISPLAY INVISIBLE (-4725 4575);
FORCEPROP 2 LAST SEC_TYPE 0402
J 0
(-4725 4575);
DISPLAY 1.021277 (-4725 4575);
PAINT ORANGE (-4725 4575);
DISPLAY INVISIBLE (-4725 4575);
FORCEADD OFFPAGE..3
(-700 1775);
FORCEPROP 2 LAST $XR11 235 
J 0
(-246 1703);
DISPLAY 0.638298 (-246 1703);
PAINT MONO (-246 1703);
FORCEPROP 2 LAST $XR10 226 
J 0
(-366 1703);
DISPLAY 0.638298 (-366 1703);
PAINT MONO (-366 1703);
FORCEPROP 2 LAST $XR9 223 
J 0
(-486 1703);
DISPLAY 0.638298 (-486 1703);
PAINT MONO (-486 1703);
FORCEPROP 2 LAST $XR8 218 
J 0
(-246 1811);
DISPLAY 0.638298 (-246 1811);
PAINT MONO (-246 1811);
FORCEPROP 2 LAST $XR7 215 
J 0
(-366 1811);
DISPLAY 0.638298 (-366 1811);
PAINT MONO (-366 1811);
FORCEPROP 2 LAST $XR6 213 
J 0
(-486 1811);
DISPLAY 0.638298 (-486 1811);
PAINT MONO (-486 1811);
FORCEPROP 2 LAST $XR5 211 
J 0
(-246 1739);
DISPLAY 0.638298 (-246 1739);
PAINT MONO (-246 1739);
FORCEPROP 2 LAST $XR4 206 
J 0
(-366 1739);
DISPLAY 0.638298 (-366 1739);
PAINT MONO (-366 1739);
FORCEPROP 2 LAST $XR3 194 
J 0
(-486 1739);
DISPLAY 0.638298 (-486 1739);
PAINT MONO (-486 1739);
FORCEPROP 2 LAST $XR2 193 
J 0
(-246 1775);
DISPLAY 0.638298 (-246 1775);
PAINT MONO (-246 1775);
FORCEPROP 2 LAST $XR1 159 
J 0
(-366 1775);
DISPLAY 0.638298 (-366 1775);
PAINT MONO (-366 1775);
FORCEPROP 2 LAST $XR0 138 
J 0
(-486 1775);
DISPLAY 0.638298 (-486 1775);
PAINT MONO (-486 1775);
FORCEPROP 2 LAST ROOM PVCCIN_CPU0_VR
J 0
(-1100 1850);
DISPLAY 1.361702 (-1100 1850);
PAINT ORANGE (-1100 1850);
DISPLAY INVISIBLE (-1100 1850);
FORCEPROP 2 LAST CDS_LIB mstr_standard
J 0
(-700 1775);
PAINT ORANGE (-700 1775);
DISPLAY INVISIBLE (-700 1775);
FORCEPROP 2 LAST PATH I14
J 0
(-500 1850);
DISPLAY 1.021277 (-500 1850);
PAINT ORANGE (-500 1850);
DISPLAY INVISIBLE (-500 1850);
FORCEPROP 1 LAST OFFPAGE TRUE
J 0
(-375 1650);
DISPLAY 1.170213 (-375 1650);
PAINT GREEN (-375 1650);
DISPLAY INVISIBLE (-375 1650);
FORCEPROP 1 LAST COMMENT_BODY TRUE
J 0
(-750 1675);
DISPLAY 1.170213 (-750 1675);
PAINT GREEN (-750 1675);
DISPLAY INVISIBLE (-750 1675);
FORCEADD OFFPAGE..1
R 2
(-700 1525);
FORCEPROP 2 LAST $XR11 226 
J 0
(-274 1453);
DISPLAY 0.638298 (-274 1453);
PAINT MONO (-274 1453);
FORCEPROP 2 LAST $XR10 223 
J 0
(-394 1453);
DISPLAY 0.638298 (-394 1453);
PAINT MONO (-394 1453);
FORCEPROP 2 LAST $XR9 218 
J 0
(-514 1453);
DISPLAY 0.638298 (-514 1453);
PAINT MONO (-514 1453);
FORCEPROP 2 LAST $XR8 215 
J 0
(-274 1561);
DISPLAY 0.638298 (-274 1561);
PAINT MONO (-274 1561);
FORCEPROP 2 LAST $XR7 206 
J 0
(-394 1561);
DISPLAY 0.638298 (-394 1561);
PAINT MONO (-394 1561);
FORCEPROP 2 LAST $XR6 194 
J 0
(-514 1561);
DISPLAY 0.638298 (-514 1561);
PAINT MONO (-514 1561);
FORCEPROP 2 LAST $XR5 193 
J 0
(-274 1489);
DISPLAY 0.638298 (-274 1489);
PAINT MONO (-274 1489);
FORCEPROP 2 LAST $XR4 235 
J 0
(-394 1489);
DISPLAY 0.638298 (-394 1489);
PAINT MONO (-394 1489);
FORCEPROP 2 LAST $XR3 213 
J 0
(-514 1489);
DISPLAY 0.638298 (-514 1489);
PAINT MONO (-514 1489);
FORCEPROP 2 LAST $XR2 211 
J 0
(-274 1525);
DISPLAY 0.638298 (-274 1525);
PAINT MONO (-274 1525);
FORCEPROP 2 LAST $XR1 159 
J 0
(-394 1525);
DISPLAY 0.638298 (-394 1525);
PAINT MONO (-394 1525);
FORCEPROP 2 LAST $XR0 138 
J 0
(-514 1525);
DISPLAY 0.638298 (-514 1525);
PAINT MONO (-514 1525);
FORCEPROP 2 LAST ROOM PVCCIN_CPU0_VR
J 0
(-1125 1600);
DISPLAY 1.361702 (-1125 1600);
PAINT ORANGE (-1125 1600);
DISPLAY INVISIBLE (-1125 1600);
FORCEPROP 2 LAST CDS_LIB mstr_standard
J 0
(-700 1525);
PAINT ORANGE (-700 1525);
DISPLAY INVISIBLE (-700 1525);
FORCEPROP 2 LAST PATH I15
J 0
(-525 1600);
DISPLAY 1.021277 (-525 1600);
PAINT ORANGE (-525 1600);
DISPLAY INVISIBLE (-525 1600);
FORCEPROP 1 LAST OFFPAGE TRUE
J 2
(-1025 1400);
DISPLAY 1.170213 (-1025 1400);
PAINT GREEN (-1025 1400);
DISPLAY INVISIBLE (-1025 1400);
FORCEPROP 1 LAST COMMENT_BODY TRUE
J 2
(-825 1425);
DISPLAY 1.170213 (-825 1425);
PAINT GREEN (-825 1425);
DISPLAY INVISIBLE (-825 1425);
FORCEADD PXE1610B..1
(-3800 2575);
FORCEPROP 2 LASTPIN (-4250 3275) $PN 17
J 2
(-4260 3285);
DISPLAY 0.617021 (-4260 3285);
PAINT MONO (-4260 3285);
FORCEPROP 2 LASTPIN (-4250 1925) $PN 42
J 2
(-4260 1935);
DISPLAY 0.617021 (-4260 1935);
PAINT MONO (-4260 1935);
FORCEPROP 2 LASTPIN (-4250 1875) $PN 37
J 2
(-4260 1885);
DISPLAY 0.617021 (-4260 1885);
PAINT MONO (-4260 1885);
FORCEPROP 2 LASTPIN (-4250 2025) $PN 10
J 2
(-4260 2035);
DISPLAY 0.617021 (-4260 2035);
PAINT MONO (-4260 2035);
FORCEPROP 2 LASTPIN (-4250 2125) $PN 46
J 2
(-4260 2135);
DISPLAY 0.617021 (-4260 2135);
PAINT MONO (-4260 2135);
FORCEPROP 2 LASTPIN (-4250 2475) $PN 22
J 2
(-4260 2485);
DISPLAY 0.617021 (-4260 2485);
PAINT MONO (-4260 2485);
FORCEPROP 2 LASTPIN (-4250 2375) $PN 36
J 2
(-4260 2385);
DISPLAY 0.617021 (-4260 2385);
PAINT MONO (-4260 2385);
FORCEPROP 2 LASTPIN (-4250 2225) $PN 12
J 2
(-4260 2235);
DISPLAY 0.617021 (-4260 2235);
PAINT MONO (-4260 2235);
FORCEPROP 2 LASTPIN (-4250 2175) $PN 45
J 2
(-4260 2185);
DISPLAY 0.617021 (-4260 2185);
PAINT MONO (-4260 2185);
FORCEPROP 2 LASTPIN (-4250 2525) $PN 21
J 2
(-4260 2535);
DISPLAY 0.617021 (-4260 2535);
PAINT MONO (-4260 2535);
FORCEPROP 2 LASTPIN (-4250 2875) $PN 24
J 2
(-4260 2885);
DISPLAY 0.617021 (-4260 2885);
PAINT MONO (-4260 2885);
FORCEPROP 2 LASTPIN (-4250 2675) $PN 32
J 2
(-4260 2685);
DISPLAY 0.617021 (-4260 2685);
PAINT MONO (-4260 2685);
FORCEPROP 2 LASTPIN (-4250 2625) $PN 34
J 2
(-4260 2635);
DISPLAY 0.617021 (-4260 2635);
PAINT MONO (-4260 2635);
FORCEPROP 2 LASTPIN (-4250 2925) $PN 33
J 2
(-4260 2935);
DISPLAY 0.617021 (-4260 2935);
PAINT MONO (-4260 2935);
FORCEPROP 2 LASTPIN (-4250 2775) $PN 28
J 2
(-4260 2785);
DISPLAY 0.617021 (-4260 2785);
PAINT MONO (-4260 2785);
FORCEPROP 2 LASTPIN (-4250 2725) $PN 30
J 2
(-4260 2735);
DISPLAY 0.617021 (-4260 2735);
PAINT MONO (-4260 2735);
FORCEPROP 2 LASTPIN (-4250 3125) $PN 25
J 2
(-4260 3135);
DISPLAY 0.617021 (-4260 3135);
PAINT MONO (-4260 3135);
FORCEPROP 2 LASTPIN (-3350 2325) $PN 4
J 0
(-3340 2335);
DISPLAY 0.617021 (-3340 2335);
PAINT MONO (-3340 2335);
FORCEPROP 2 LASTPIN (-3350 2275) $PN 3
J 0
(-3340 2285);
DISPLAY 0.617021 (-3340 2285);
PAINT MONO (-3340 2285);
FORCEPROP 2 LASTPIN (-3350 3225) $PN 14
J 0
(-3340 3235);
DISPLAY 0.617021 (-3340 3235);
PAINT MONO (-3340 3235);
FORCEPROP 2 LASTPIN (-3350 2675) $PN 15
J 0
(-3340 2685);
DISPLAY 0.617021 (-3340 2685);
PAINT MONO (-3340 2685);
FORCEPROP 2 LASTPIN (-4250 2275) $PN 43
J 2
(-4260 2285);
DISPLAY 0.617021 (-4260 2285);
PAINT MONO (-4260 2285);
FORCEPROP 2 LASTPIN (-3350 1825) $PN 49
J 0
(-3340 1835);
DISPLAY 0.617021 (-3340 1835);
PAINT MONO (-3340 1835);
FORCEPROP 2 LASTPIN (-3350 2025) $PN 9
J 0
(-3340 2035);
DISPLAY 0.617021 (-3340 2035);
PAINT MONO (-3340 2035);
FORCEPROP 2 LASTPIN (-3350 2425) $PN 6
J 0
(-3340 2435);
DISPLAY 0.617021 (-3340 2435);
PAINT MONO (-3340 2435);
FORCEPROP 2 LASTPIN (-3350 2375) $PN 5
J 0
(-3340 2385);
DISPLAY 0.617021 (-3340 2385);
PAINT MONO (-3340 2385);
FORCEPROP 2 LASTPIN (-3350 2225) $PN 2
J 0
(-3340 2235);
DISPLAY 0.617021 (-3340 2235);
PAINT MONO (-3340 2235);
FORCEPROP 2 LASTPIN (-3350 2125) $PN 8
J 0
(-3340 2135);
DISPLAY 0.617021 (-3340 2135);
PAINT MONO (-3340 2135);
FORCEPROP 2 LASTPIN (-3350 2775) $PN 48
J 0
(-3340 2785);
DISPLAY 0.617021 (-3340 2785);
PAINT MONO (-3340 2785);
FORCEPROP 2 LASTPIN (-3350 3075) $PN 40
J 0
(-3340 3085);
DISPLAY 0.617021 (-3340 3085);
PAINT MONO (-3340 3085);
FORCEPROP 2 LASTPIN (-3350 2475) $PN 7
J 0
(-3340 2485);
DISPLAY 0.617021 (-3340 2485);
PAINT MONO (-3340 2485);
FORCEPROP 2 LASTPIN (-3350 2875) $PN 19
J 0
(-3340 2885);
DISPLAY 0.617021 (-3340 2885);
PAINT MONO (-3340 2885);
FORCEPROP 2 LASTPIN (-4250 1775) $PN 44
J 2
(-4260 1785);
DISPLAY 0.617021 (-4260 1785);
PAINT MONO (-4260 1785);
FORCEPROP 2 LASTPIN (-4250 1725) $PN 41
J 2
(-4260 1735);
DISPLAY 0.617021 (-4260 1735);
PAINT MONO (-4260 1735);
FORCEPROP 2 LASTPIN (-4250 1825) $PN 38
J 2
(-4260 1835);
DISPLAY 0.617021 (-4260 1835);
PAINT MONO (-4260 1835);
FORCEPROP 2 LASTPIN (-4250 3375) $PN 47
J 2
(-4260 3385);
DISPLAY 0.617021 (-4260 3385);
PAINT MONO (-4260 3385);
FORCEPROP 1 LAST PART_NUMBER H79206-001
J 0
(-4200 1625);
DISPLAY 0.617021 (-4200 1625);
PAINT BLUE (-4200 1625);
FORCEPROP 2 LASTPIN (-3350 3325) $PN 11
J 0
(-3340 3335);
DISPLAY 0.617021 (-3340 3335);
PAINT MONO (-3340 3335);
FORCEPROP 2 LASTPIN (-3350 2975) $PN 13
J 0
(-3340 2985);
DISPLAY 0.617021 (-3340 2985);
PAINT MONO (-3340 2985);
FORCEPROP 2 LASTPIN (-4250 3025) $PN 29
J 2
(-4260 3035);
DISPLAY 0.617021 (-4260 3035);
PAINT MONO (-4260 3035);
FORCEPROP 2 LASTPIN (-4250 3075) $PN 27
J 2
(-4260 3085);
DISPLAY 0.617021 (-4260 3085);
PAINT MONO (-4260 3085);
FORCEPROP 1 LAST MATERIAL IC
J 0
(-4200 3500);
DISPLAY 0.617021 (-4200 3500);
PAINT SKYBLUE (-4200 3500);
FORCEPROP 2 LASTPIN (-3350 3275) $PN 20
J 0
(-3340 3285);
DISPLAY 0.617021 (-3340 3285);
PAINT MONO (-3340 3285);
FORCEPROP 2 LASTPIN (-3350 2525) $PN 1
J 0
(-3340 2535);
DISPLAY 0.617021 (-3340 2535);
PAINT MONO (-3340 2535);
FORCEPROP 2 LASTPIN (-3350 2725) $PN 18
J 0
(-3340 2735);
DISPLAY 0.617021 (-3340 2735);
PAINT MONO (-3340 2735);
FORCEPROP 2 LASTPIN (-3350 2625) $PN 16
J 0
(-3340 2635);
DISPLAY 0.617021 (-3340 2635);
PAINT MONO (-3340 2635);
FORCEPROP 2 LASTPIN (-4250 2825) $PN 26
J 2
(-4260 2835);
DISPLAY 0.617021 (-4260 2835);
PAINT MONO (-4260 2835);
FORCEPROP 2 LASTPIN (-3350 3125) $PN 39
J 0
(-3340 3135);
DISPLAY 0.617021 (-3340 3135);
PAINT MONO (-3340 3135);
FORCEPROP 1 LAST LOCATION EU4D4
J 0
(-4200 3550);
DISPLAY 0.617021 (-4200 3550);
PAINT AQUA (-4200 3550);
FORCEPROP 2 LASTPIN (-4250 3175) $PN 23
J 2
(-4260 3185);
DISPLAY 0.617021 (-4260 3185);
PAINT MONO (-4260 3185);
FORCEPROP 2 LASTPIN (-4250 2975) $PN 31
J 2
(-4260 2985);
DISPLAY 0.617021 (-4260 2985);
PAINT MONO (-4260 2985);
FORCEPROP 2 LASTPIN (-4250 2425) $PN 35
J 2
(-4260 2435);
DISPLAY 0.617021 (-4260 2435);
PAINT MONO (-4260 2435);
FORCEPROP 2 LAST CDS_LOCATION EU4D4
J 0
(-4200 3550);
DISPLAY 0.617021 (-4200 3550);
PAINT AQUA (-4200 3550);
DISPLAY INVISIBLE (-4200 3550);
FORCEPROP 1 LAST PACK_TYPE QFN
J 0
(-4200 3600);
PAINT SKYBLUE (-4200 3600);
DISPLAY INVISIBLE (-4200 3600);
FORCEPROP 2 LAST CDS_SEC 1
J 0
(-4200 3600);
PAINT MONO (-4200 3600);
DISPLAY INVISIBLE (-4200 3600);
FORCEPROP 2 LAST $SEC 1
J 0
(-4200 3600);
PAINT MONO (-4200 3600);
DISPLAY INVISIBLE (-4200 3600);
FORCEPROP 2 LAST CDS_LIB mstr_controller
J 0
(-3800 2575);
PAINT ORANGE (-3800 2575);
DISPLAY INVISIBLE (-3800 2575);
FORCEPROP 1 LAST CDS_LMAN_SYM_OUTLINE -400,900,400,-900
J 0
(-3800 2575);
DISPLAY 0.468085 (-3800 2575);
PAINT GREEN (-3800 2575);
DISPLAY INVISIBLE (-3800 2575);
FORCEPROP 1 LAST PATH I155
J 0
(-3700 3501);
PAINT WHITE (-3700 3501);
DISPLAY INVISIBLE (-3700 3501);
FORCEADD SC22P50V2JN-4GP..1
R 1
(-6750 3350);
FORCEPROP 2 LAST TYPE NPO
J 0
(-6875 2975);
DISPLAY 0.638298 (-6875 2975);
PAINT GREEN (-6875 2975);
FORCEPROP 2 LAST RATED 50V
J 0
(-6875 3025);
DISPLAY 0.638298 (-6875 3025);
PAINT GREEN (-6875 3025);
FORCEPROP 2 LAST TOLERANCE 5%
J 0
(-6875 3075);
DISPLAY 0.638298 (-6875 3075);
PAINT GREEN (-6875 3075);
FORCEPROP 1 LAST LOCATION CF1
J 0
(-6880 3225);
DISPLAY 0.617021 (-6880 3225);
PAINT GREEN (-6880 3225);
FORCEPROP 1 LAST VALUE SC22P50V2JN-4GP
J 0
(-6875 3175);
DISPLAY 0.617021 (-6875 3175);
PAINT GREEN (-6875 3175);
FORCEPROP 2 LAST PACK_SIZE 0402
J 0
(-6725 3125);
DISPLAY 0.638298 (-6725 3125);
PAINT GREEN (-6725 3125);
FORCEPROP 2 LAST ATTRIBUTE 22PF
J 0
(-6875 3125);
DISPLAY 0.638298 (-6875 3125);
PAINT GREEN (-6875 3125);
FORCEPROP 0 LAST GROUP POWER_FAIR
J 0
(-6875 3275);
DISPLAY 0.638298 (-6875 3275);
PAINT BROWN (-6875 3275);
DISPLAY BOTH (-6875 3275);
FORCEPROP 2 LAST CDS_LIB w_hdl
R 1
J 0
(-6750 3350);
PAINT MONO (-6750 3350);
DISPLAY INVISIBLE (-6750 3350);
FORCEPROP 1 LAST CDS_LMAN_SYM_OUTLINE -50,25,50,-25
R 1
J 0
(-6750 3350);
DISPLAY 0.468085 (-6750 3350);
PAINT GREEN (-6750 3350);
DISPLAY INVISIBLE (-6750 3350);
FORCEPROP 1 LAST PATH I168
R 1
J 0
(-6750 3350);
DISPLAY 0.617021 (-6750 3350);
PAINT GREEN (-6750 3350);
DISPLAY INVISIBLE (-6750 3350);
FORCEPROP 1 LAST PACK_TYPE SMD-BCG
R 1
J 0
(-6750 3350);
DISPLAY 0.617021 (-6750 3350);
PAINT GREEN (-6750 3350);
DISPLAY INVISIBLE (-6750 3350);
FORCEPROP 1 LAST PART_NUMBER 78.22034.1FL
R 1
J 0
(-6750 3350);
DISPLAY 0.617021 (-6750 3350);
PAINT GREEN (-6750 3350);
DISPLAY INVISIBLE (-6750 3350);
FORCEADD SC22P50V2JN-4GP..1
R 1
(-6300 3350);
FORCEPROP 1 LAST LOCATION CF2
J 0
(-6455 3225);
DISPLAY 0.617021 (-6455 3225);
PAINT GREEN (-6455 3225);
FORCEPROP 2 LAST PACK_SIZE 0402
J 0
(-6300 3125);
DISPLAY 0.638298 (-6300 3125);
PAINT GREEN (-6300 3125);
FORCEPROP 2 LAST ATTRIBUTE 22PF
J 0
(-6450 3125);
DISPLAY 0.638298 (-6450 3125);
PAINT GREEN (-6450 3125);
FORCEPROP 2 LAST TYPE NPO
J 0
(-6450 2975);
DISPLAY 0.638298 (-6450 2975);
PAINT GREEN (-6450 2975);
FORCEPROP 2 LAST RATED 50V
J 0
(-6450 3025);
DISPLAY 0.638298 (-6450 3025);
PAINT GREEN (-6450 3025);
FORCEPROP 2 LAST TOLERANCE 5%
J 0
(-6450 3075);
DISPLAY 0.638298 (-6450 3075);
PAINT GREEN (-6450 3075);
FORCEPROP 0 LAST GROUP POWER_FAIR
J 0
(-6425 3275);
DISPLAY 0.638298 (-6425 3275);
PAINT BROWN (-6425 3275);
DISPLAY BOTH (-6425 3275);
FORCEPROP 1 LAST VALUE SC22P50V2JN-4GP
J 0
(-6450 3175);
DISPLAY 0.617021 (-6450 3175);
PAINT GREEN (-6450 3175);
FORCEPROP 1 LAST CDS_LMAN_SYM_OUTLINE -50,25,50,-25
R 1
J 0
(-6300 3350);
DISPLAY 0.468085 (-6300 3350);
PAINT GREEN (-6300 3350);
DISPLAY INVISIBLE (-6300 3350);
FORCEPROP 2 LAST CDS_LIB w_hdl
J 0
(-6300 3350);
PAINT MONO (-6300 3350);
DISPLAY INVISIBLE (-6300 3350);
FORCEPROP 1 LAST PATH I169
R 1
J 0
(-6300 3350);
DISPLAY 0.617021 (-6300 3350);
PAINT GREEN (-6300 3350);
DISPLAY INVISIBLE (-6300 3350);
FORCEPROP 1 LAST PACK_TYPE SMD-BCG
R 1
J 0
(-6300 3350);
DISPLAY 0.617021 (-6300 3350);
PAINT GREEN (-6300 3350);
DISPLAY INVISIBLE (-6300 3350);
FORCEPROP 1 LAST PART_NUMBER 78.22034.1FL
R 1
J 0
(-6300 3350);
DISPLAY 0.617021 (-6300 3350);
PAINT GREEN (-6300 3350);
DISPLAY INVISIBLE (-6300 3350);
FORCEADD OFFPAGE..1
R 2
(-1075 1175);
FORCEPROP 2 LAST $XR0 201 
J 0
(-889 1175);
DISPLAY 0.638298 (-889 1175);
PAINT MONO (-889 1175);
FORCEPROP 2 LAST ROOM PVCCIN_CPU0_VR
J 0
(-1500 1250);
DISPLAY 1.361702 (-1500 1250);
PAINT ORANGE (-1500 1250);
DISPLAY INVISIBLE (-1500 1250);
FORCEPROP 2 LAST CDS_LIB mstr_standard
J 2
(-1075 1175);
PAINT ORANGE (-1075 1175);
DISPLAY INVISIBLE (-1075 1175);
FORCEPROP 2 LAST PATH I17
J 0
(-900 1250);
DISPLAY 1.021277 (-900 1250);
PAINT ORANGE (-900 1250);
DISPLAY INVISIBLE (-900 1250);
FORCEPROP 1 LAST OFFPAGE TRUE
J 2
(-1400 1050);
DISPLAY 1.170213 (-1400 1050);
PAINT GREEN (-1400 1050);
DISPLAY INVISIBLE (-1400 1050);
FORCEPROP 1 LAST COMMENT_BODY TRUE
J 2
(-1200 1075);
DISPLAY 1.170213 (-1200 1075);
PAINT GREEN (-1200 1075);
DISPLAY INVISIBLE (-1200 1075);
FORCEADD SC22P50V2JN-4GP..1
R 1
(-5825 3350);
FORCEPROP 0 LAST GROUP POWER_FAIR
J 0
(-5950 3275);
DISPLAY 0.638298 (-5950 3275);
PAINT BROWN (-5950 3275);
DISPLAY BOTH (-5950 3275);
FORCEPROP 1 LAST LOCATION CF3
J 0
(-5980 3225);
DISPLAY 0.617021 (-5980 3225);
PAINT GREEN (-5980 3225);
FORCEPROP 1 LAST VALUE SC22P50V2JN-4GP
J 0
(-5975 3175);
DISPLAY 0.617021 (-5975 3175);
PAINT GREEN (-5975 3175);
FORCEPROP 2 LAST ATTRIBUTE 22PF
J 0
(-5975 3125);
DISPLAY 0.638298 (-5975 3125);
PAINT GREEN (-5975 3125);
FORCEPROP 2 LAST TOLERANCE 5%
J 0
(-5975 3075);
DISPLAY 0.638298 (-5975 3075);
PAINT GREEN (-5975 3075);
FORCEPROP 2 LAST PACK_SIZE 0402
J 0
(-5800 3125);
DISPLAY 0.638298 (-5800 3125);
PAINT GREEN (-5800 3125);
FORCEPROP 2 LAST TYPE NPO
J 0
(-5975 2975);
DISPLAY 0.638298 (-5975 2975);
PAINT GREEN (-5975 2975);
FORCEPROP 2 LAST RATED 50V
J 0
(-5975 3025);
DISPLAY 0.638298 (-5975 3025);
PAINT GREEN (-5975 3025);
FORCEPROP 1 LAST CDS_LMAN_SYM_OUTLINE -50,25,50,-25
R 1
J 0
(-5825 3350);
DISPLAY 0.468085 (-5825 3350);
PAINT GREEN (-5825 3350);
DISPLAY INVISIBLE (-5825 3350);
FORCEPROP 2 LAST CDS_LIB w_hdl
J 0
(-5825 3350);
PAINT MONO (-5825 3350);
DISPLAY INVISIBLE (-5825 3350);
FORCEPROP 1 LAST PATH I170
R 1
J 0
(-5825 3350);
DISPLAY 0.617021 (-5825 3350);
PAINT GREEN (-5825 3350);
DISPLAY INVISIBLE (-5825 3350);
FORCEPROP 1 LAST PACK_TYPE SMD-BCG
R 1
J 0
(-5825 3350);
DISPLAY 0.617021 (-5825 3350);
PAINT GREEN (-5825 3350);
DISPLAY INVISIBLE (-5825 3350);
FORCEPROP 1 LAST PART_NUMBER 78.22034.1FL
R 1
J 0
(-5825 3350);
DISPLAY 0.617021 (-5825 3350);
PAINT GREEN (-5825 3350);
DISPLAY INVISIBLE (-5825 3350);
FORCEADD SC22P50V2JN-4GP..1
R 1
(-5425 3350);
FORCEPROP 1 LAST VALUE SC22P50V2JN-4GP
J 0
(-5550 3175);
DISPLAY 0.617021 (-5550 3175);
PAINT GREEN (-5550 3175);
FORCEPROP 2 LAST PACK_SIZE 0402
J 0
(-5400 3125);
DISPLAY 0.638298 (-5400 3125);
PAINT GREEN (-5400 3125);
FORCEPROP 2 LAST ATTRIBUTE 22PF
J 0
(-5550 3125);
DISPLAY 0.638298 (-5550 3125);
PAINT GREEN (-5550 3125);
FORCEPROP 1 LAST LOCATION CF4
J 0
(-5555 3225);
DISPLAY 0.617021 (-5555 3225);
PAINT GREEN (-5555 3225);
FORCEPROP 2 LAST RATED 50V
J 0
(-5550 3025);
DISPLAY 0.638298 (-5550 3025);
PAINT GREEN (-5550 3025);
FORCEPROP 2 LAST TOLERANCE 5%
J 0
(-5550 3075);
DISPLAY 0.638298 (-5550 3075);
PAINT GREEN (-5550 3075);
FORCEPROP 0 LAST GROUP POWER_FAIR
J 0
(-5525 3275);
DISPLAY 0.638298 (-5525 3275);
PAINT BROWN (-5525 3275);
DISPLAY BOTH (-5525 3275);
FORCEPROP 2 LAST TYPE NPO
J 0
(-5550 2975);
DISPLAY 0.638298 (-5550 2975);
PAINT GREEN (-5550 2975);
FORCEPROP 1 LAST PART_NUMBER 78.22034.1FL
R 1
J 0
(-5425 3350);
DISPLAY 0.617021 (-5425 3350);
PAINT GREEN (-5425 3350);
DISPLAY INVISIBLE (-5425 3350);
FORCEPROP 1 LAST PACK_TYPE SMD-BCG
R 1
J 0
(-5425 3350);
DISPLAY 0.617021 (-5425 3350);
PAINT GREEN (-5425 3350);
DISPLAY INVISIBLE (-5425 3350);
FORCEPROP 1 LAST PATH I171
R 1
J 0
(-5425 3350);
DISPLAY 0.617021 (-5425 3350);
PAINT GREEN (-5425 3350);
DISPLAY INVISIBLE (-5425 3350);
FORCEPROP 2 LAST CDS_LIB w_hdl
J 0
(-5425 3350);
PAINT MONO (-5425 3350);
DISPLAY INVISIBLE (-5425 3350);
FORCEPROP 1 LAST CDS_LMAN_SYM_OUTLINE -50,25,50,-25
R 1
J 0
(-5425 3350);
DISPLAY 0.468085 (-5425 3350);
PAINT GREEN (-5425 3350);
DISPLAY INVISIBLE (-5425 3350);
FORCEADD SC22P50V2JN-4GP..1
R 1
(-5025 3350);
FORCEPROP 1 LAST VALUE SC22P50V2JN-4GP
J 0
(-5150 3175);
DISPLAY 0.617021 (-5150 3175);
PAINT GREEN (-5150 3175);
FORCEPROP 0 LAST GROUP POWER_FAIR
J 0
(-5100 3275);
DISPLAY 0.638298 (-5100 3275);
PAINT BROWN (-5100 3275);
DISPLAY BOTH (-5100 3275);
FORCEPROP 1 LAST LOCATION CF5
J 0
(-5155 3225);
DISPLAY 0.617021 (-5155 3225);
PAINT GREEN (-5155 3225);
FORCEPROP 2 LAST ATTRIBUTE 22PF
J 0
(-5150 3125);
DISPLAY 0.638298 (-5150 3125);
PAINT GREEN (-5150 3125);
FORCEPROP 2 LAST PACK_SIZE 0402
J 0
(-5000 3125);
DISPLAY 0.638298 (-5000 3125);
PAINT GREEN (-5000 3125);
FORCEPROP 2 LAST TYPE NPO
J 0
(-5150 2975);
DISPLAY 0.638298 (-5150 2975);
PAINT GREEN (-5150 2975);
FORCEPROP 2 LAST RATED 50V
J 0
(-5150 3025);
DISPLAY 0.638298 (-5150 3025);
PAINT GREEN (-5150 3025);
FORCEPROP 2 LAST TOLERANCE 5%
J 0
(-5150 3075);
DISPLAY 0.638298 (-5150 3075);
PAINT GREEN (-5150 3075);
FORCEPROP 2 LAST CDS_LIB w_hdl
J 0
(-5025 3350);
PAINT MONO (-5025 3350);
DISPLAY INVISIBLE (-5025 3350);
FORCEPROP 1 LAST PATH I172
R 1
J 0
(-5025 3350);
DISPLAY 0.617021 (-5025 3350);
PAINT GREEN (-5025 3350);
DISPLAY INVISIBLE (-5025 3350);
FORCEPROP 1 LAST CDS_LMAN_SYM_OUTLINE -50,25,50,-25
R 1
J 0
(-5025 3350);
DISPLAY 0.468085 (-5025 3350);
PAINT GREEN (-5025 3350);
DISPLAY INVISIBLE (-5025 3350);
FORCEPROP 1 LAST PACK_TYPE SMD-BCG
R 1
J 0
(-5025 3350);
DISPLAY 0.617021 (-5025 3350);
PAINT GREEN (-5025 3350);
DISPLAY INVISIBLE (-5025 3350);
FORCEPROP 1 LAST PART_NUMBER 78.22034.1FL
R 1
J 0
(-5025 3350);
DISPLAY 0.617021 (-5025 3350);
PAINT GREEN (-5025 3350);
DISPLAY INVISIBLE (-5025 3350);
FORCEADD SC22P50V2JN-4GP..1
R 1
(-5800 1325);
FORCEPROP 2 LAST PACK_SIZE 0402
J 0
(-5850 1050);
DISPLAY 0.638298 (-5850 1050);
PAINT GREEN (-5850 1050);
FORCEPROP 2 LAST TYPE NPO
J 0
(-5975 1050);
DISPLAY 0.638298 (-5975 1050);
PAINT GREEN (-5975 1050);
FORCEPROP 2 LAST TOLERANCE 5%
J 0
(-5850 1100);
DISPLAY 0.638298 (-5850 1100);
PAINT GREEN (-5850 1100);
FORCEPROP 2 LAST ATTRIBUTE 22PF
J 0
(-5975 1100);
DISPLAY 0.638298 (-5975 1100);
PAINT GREEN (-5975 1100);
FORCEPROP 1 LAST LOCATION CF6
J 0
(-5980 1200);
DISPLAY 0.617021 (-5980 1200);
PAINT GREEN (-5980 1200);
FORCEPROP 1 LAST VALUE SC22P50V2JN-4GP
J 0
(-5975 1150);
DISPLAY 0.617021 (-5975 1150);
PAINT GREEN (-5975 1150);
FORCEPROP 2 LAST RATED 50V
J 0
(-5750 1100);
DISPLAY 0.638298 (-5750 1100);
PAINT GREEN (-5750 1100);
FORCEPROP 0 LAST GROUP POWER_FAIR
J 0
(-5925 1250);
DISPLAY 0.638298 (-5925 1250);
PAINT BROWN (-5925 1250);
DISPLAY BOTH (-5925 1250);
FORCEPROP 2 LAST CDS_LIB w_hdl
J 0
(-5800 1325);
PAINT MONO (-5800 1325);
DISPLAY INVISIBLE (-5800 1325);
FORCEPROP 1 LAST PATH I173
R 1
J 0
(-5800 1325);
DISPLAY 0.617021 (-5800 1325);
PAINT GREEN (-5800 1325);
DISPLAY INVISIBLE (-5800 1325);
FORCEPROP 1 LAST CDS_LMAN_SYM_OUTLINE -50,25,50,-25
R 1
J 0
(-5800 1325);
DISPLAY 0.468085 (-5800 1325);
PAINT GREEN (-5800 1325);
DISPLAY INVISIBLE (-5800 1325);
FORCEPROP 1 LAST PART_NUMBER 78.22034.1FL
R 1
J 0
(-5800 1325);
DISPLAY 0.617021 (-5800 1325);
PAINT GREEN (-5800 1325);
DISPLAY INVISIBLE (-5800 1325);
FORCEPROP 1 LAST PACK_TYPE SMD-BCG
R 1
J 0
(-5800 1325);
DISPLAY 0.617021 (-5800 1325);
PAINT GREEN (-5800 1325);
DISPLAY INVISIBLE (-5800 1325);
FORCEADD PVCCIO_CPU0..1
(-1275 3950);
FORCEPROP 3 LASTPIN (-1275 3900) SIG_NAME PVCCIO_CPU0\g
J 0
(-1265 3910);
DISPLAY 0.659574 (-1265 3910);
PAINT MONO (-1265 3910);
DISPLAY INVISIBLE (-1265 3910);
FORCEPROP 1 LAST VOLTAGE 1.1V
J 0
(-1320 3907);
DISPLAY 0.340426 (-1320 3907);
PAINT SKYBLUE (-1320 3907);
DISPLAY INVISIBLE (-1320 3907);
FORCEPROP 2 LAST CDS_LIB mstr_symbols
J 0
(-1275 3950);
PAINT ORANGE (-1275 3950);
DISPLAY INVISIBLE (-1275 3950);
FORCEPROP 1 LAST PATH I18
J 0
(-1225 3975);
DISPLAY 0.872340 (-1225 3975);
PAINT AQUA (-1225 3975);
DISPLAY INVISIBLE (-1225 3975);
FORCEPROP 1 LAST BODY_TYPE PLUMBING
J 0
(-1320 3907);
DISPLAY 0.340426 (-1320 3907);
PAINT GREEN (-1320 3907);
DISPLAY INVISIBLE (-1320 3907);
FORCEPROP 1 LAST HDL_POWER PVCCIO_CPU0
J 1
(-1275 4000);
DISPLAY 0.872340 (-1275 4000);
PAINT GREEN (-1275 4000);
DISPLAY INVISIBLE (-1275 4000);
FORCEADD RES..1
(-5800 1425);
FORCEPROP 1 LAST MATERIAL CHIP
J 0
(-5675 1525);
DISPLAY 0.617021 (-5675 1525);
PAINT SKYBLUE (-5675 1525);
FORCEPROP 1 LAST WATTAGE 1/16W
J 2
(-5475 1475);
DISPLAY 0.617021 (-5475 1475);
PAINT SKYBLUE (-5475 1475);
FORCEPROP 1 LAST PACK_TYPE 0402
J 0
(-5725 1475);
DISPLAY 0.617021 (-5725 1475);
PAINT SKYBLUE (-5725 1475);
FORCEPROP 1 LAST PART_NUMBER G85996-004
J 0
(-6000 1475);
DISPLAY 0.617021 (-6000 1475);
PAINT BLUE (-6000 1475);
FORCEPROP 1 LASTPIN (-5900 1425) $PN 1
J 0
(-5888 1437);
DISPLAY 0.787234 (-5888 1437);
PAINT ORANGE (-5888 1437);
FORCEPROP 1 LAST TOLERANCE 0.1%
J 0
(-5800 1525);
DISPLAY 0.617021 (-5800 1525);
PAINT SKYBLUE (-5800 1525);
FORCEPROP 1 LAST VALUE 1.0K
J 2
(-5825 1525);
DISPLAY 0.617021 (-5825 1525);
PAINT SKYBLUE (-5825 1525);
FORCEPROP 1 LAST LOCATION RF6
J 0
(-6000 1525);
DISPLAY 0.617021 (-6000 1525);
PAINT AQUA (-6000 1525);
FORCEPROP 1 LASTPIN (-5700 1425) $PN 2
J 0
(-5738 1437);
DISPLAY 0.787234 (-5738 1437);
PAINT ORANGE (-5738 1437);
FORCEPROP 0 LAST GROUP POWER_FAIR
J 0
(-5925 1375);
DISPLAY 0.638298 (-5925 1375);
PAINT BROWN (-5925 1375);
DISPLAY BOTH (-5925 1375);
FORCEPROP 1 LAST PATH I180
J 0
(-5850 1575);
DISPLAY 0.978723 (-5850 1575);
PAINT WHITE (-5850 1575);
DISPLAY INVISIBLE (-5850 1575);
FORCEPROP 0 LAST ROOM SB
J 0
(-5750 1650);
DISPLAY 1.021277 (-5750 1650);
PAINT ORANGE (-5750 1650);
DISPLAY INVISIBLE (-5750 1650);
FORCEPROP 2 LAST CDS_LIB mstr_discrete
J 0
(-5800 1425);
PAINT MONO (-5800 1425);
DISPLAY INVISIBLE (-5800 1425);
FORCEPROP 0 LAST SEC 1
J 0
(-5725 1575);
DISPLAY 0.680851 (-5725 1575);
PAINT MONO (-5725 1575);
DISPLAY INVISIBLE (-5725 1575);
FORCEPROP 2 LAST SEC_TYPE 0402
J 0
(-5850 1625);
DISPLAY 1.021277 (-5850 1625);
PAINT ORANGE (-5850 1625);
DISPLAY INVISIBLE (-5850 1625);
FORCEADD RES..1
(-6750 3500);
FORCEPROP 0 LAST FAIR_SS 064.9530D.M001
J 0
(-6875 3400);
DISPLAY 0.638298 (-6875 3400);
PAINT BROWN (-6875 3400);
DISPLAY BOTH (-6875 3400);
FORCEPROP 1 LASTPIN (-6850 3500) $PN 1
J 0
(-6838 3512);
DISPLAY 0.787234 (-6838 3512);
PAINT ORANGE (-6838 3512);
FORCEPROP 1 LAST TOLERANCE 0.1%
J 0
(-6675 3650);
DISPLAY 0.617021 (-6675 3650);
PAINT SKYBLUE (-6675 3650);
FORCEPROP 1 LAST VALUE 1.0K
J 2
(-6700 3650);
DISPLAY 0.617021 (-6700 3650);
PAINT SKYBLUE (-6700 3650);
FORCEPROP 1 LAST LOCATION RF1
J 0
(-6875 3650);
DISPLAY 0.617021 (-6875 3650);
PAINT AQUA (-6875 3650);
FORCEPROP 1 LAST PART_NUMBER G85996-004
J 0
(-6875 3600);
DISPLAY 0.617021 (-6875 3600);
PAINT BLUE (-6875 3600);
FORCEPROP 1 LAST WATTAGE 1/16W
J 2
(-6750 3550);
DISPLAY 0.617021 (-6750 3550);
PAINT SKYBLUE (-6750 3550);
FORCEPROP 1 LASTPIN (-6650 3500) $PN 2
J 0
(-6688 3512);
DISPLAY 0.787234 (-6688 3512);
PAINT ORANGE (-6688 3512);
FORCEPROP 1 LAST MATERIAL CHIP
J 0
(-6675 3550);
DISPLAY 0.617021 (-6675 3550);
PAINT SKYBLUE (-6675 3550);
FORCEPROP 1 LAST PACK_TYPE 0402
J 0
(-6650 3600);
DISPLAY 0.617021 (-6650 3600);
PAINT SKYBLUE (-6650 3600);
FORCEPROP 0 LAST GROUP POWER_FAIR
J 0
(-6875 3450);
DISPLAY 0.638298 (-6875 3450);
PAINT BROWN (-6875 3450);
DISPLAY BOTH (-6875 3450);
FORCEPROP 2 LAST CDS_LIB mstr_discrete
J 0
(-6750 3500);
PAINT MONO (-6750 3500);
DISPLAY INVISIBLE (-6750 3500);
FORCEPROP 1 LAST PATH I182
J 0
(-6800 3650);
DISPLAY 0.978723 (-6800 3650);
PAINT WHITE (-6800 3650);
DISPLAY INVISIBLE (-6800 3650);
FORCEPROP 0 LAST ROOM SB
J 0
(-6700 3725);
DISPLAY 1.021277 (-6700 3725);
PAINT ORANGE (-6700 3725);
DISPLAY INVISIBLE (-6700 3725);
FORCEPROP 0 LAST SEC 1
J 0
(-6675 3650);
DISPLAY 0.680851 (-6675 3650);
PAINT MONO (-6675 3650);
DISPLAY INVISIBLE (-6675 3650);
FORCEPROP 2 LAST SEC_TYPE 0402
J 0
(-6800 3700);
DISPLAY 1.021277 (-6800 3700);
PAINT ORANGE (-6800 3700);
DISPLAY INVISIBLE (-6800 3700);
FORCEADD RES..1
(-6300 3500);
FORCEPROP 0 LAST FAIR_SS 064.9530D.M001
J 0
(-6400 3400);
DISPLAY 0.638298 (-6400 3400);
PAINT BROWN (-6400 3400);
DISPLAY BOTH (-6400 3400);
FORCEPROP 1 LAST PACK_TYPE 0402
J 0
(-6200 3600);
DISPLAY 0.617021 (-6200 3600);
PAINT SKYBLUE (-6200 3600);
FORCEPROP 0 LAST GROUP POWER_FAIR
J 0
(-6400 3450);
DISPLAY 0.638298 (-6400 3450);
PAINT BROWN (-6400 3450);
DISPLAY BOTH (-6400 3450);
FORCEPROP 1 LAST LOCATION RF2
J 0
(-6425 3650);
DISPLAY 0.617021 (-6425 3650);
PAINT AQUA (-6425 3650);
FORCEPROP 1 LAST VALUE 1.0K
J 2
(-6250 3650);
DISPLAY 0.617021 (-6250 3650);
PAINT SKYBLUE (-6250 3650);
FORCEPROP 1 LAST TOLERANCE 0.1%
J 0
(-6225 3650);
DISPLAY 0.617021 (-6225 3650);
PAINT SKYBLUE (-6225 3650);
FORCEPROP 1 LAST PART_NUMBER G85996-004
J 0
(-6425 3600);
DISPLAY 0.617021 (-6425 3600);
PAINT BLUE (-6425 3600);
FORCEPROP 1 LAST WATTAGE 1/16W
J 2
(-6300 3550);
DISPLAY 0.617021 (-6300 3550);
PAINT SKYBLUE (-6300 3550);
FORCEPROP 1 LASTPIN (-6400 3500) $PN 1
J 0
(-6388 3512);
DISPLAY 0.787234 (-6388 3512);
PAINT ORANGE (-6388 3512);
FORCEPROP 1 LASTPIN (-6200 3500) $PN 2
J 0
(-6238 3512);
DISPLAY 0.787234 (-6238 3512);
PAINT ORANGE (-6238 3512);
FORCEPROP 1 LAST MATERIAL CHIP
J 0
(-6250 3550);
DISPLAY 0.617021 (-6250 3550);
PAINT SKYBLUE (-6250 3550);
FORCEPROP 0 LAST ROOM SB
J 0
(-6250 3725);
DISPLAY 1.021277 (-6250 3725);
PAINT ORANGE (-6250 3725);
DISPLAY INVISIBLE (-6250 3725);
FORCEPROP 1 LAST PATH I183
J 0
(-6350 3650);
DISPLAY 0.978723 (-6350 3650);
PAINT WHITE (-6350 3650);
DISPLAY INVISIBLE (-6350 3650);
FORCEPROP 2 LAST CDS_LIB mstr_discrete
J 0
(-6300 3500);
PAINT MONO (-6300 3500);
DISPLAY INVISIBLE (-6300 3500);
FORCEPROP 2 LAST SEC_TYPE 0402
J 0
(-6350 3700);
DISPLAY 1.021277 (-6350 3700);
PAINT ORANGE (-6350 3700);
DISPLAY INVISIBLE (-6350 3700);
FORCEPROP 0 LAST SEC 1
J 0
(-6225 3650);
DISPLAY 0.680851 (-6225 3650);
PAINT MONO (-6225 3650);
DISPLAY INVISIBLE (-6225 3650);
FORCEADD RES..1
(-5825 3500);
FORCEPROP 0 LAST FAIR_SS 064.9530D.M001
J 0
(-5925 3400);
DISPLAY 0.638298 (-5925 3400);
PAINT BROWN (-5925 3400);
DISPLAY BOTH (-5925 3400);
FORCEPROP 1 LAST PACK_TYPE 0402
J 0
(-5725 3600);
DISPLAY 0.617021 (-5725 3600);
PAINT SKYBLUE (-5725 3600);
FORCEPROP 1 LAST MATERIAL CHIP
J 0
(-5775 3550);
DISPLAY 0.617021 (-5775 3550);
PAINT SKYBLUE (-5775 3550);
FORCEPROP 0 LAST GROUP POWER_FAIR
J 0
(-5925 3450);
DISPLAY 0.638298 (-5925 3450);
PAINT BROWN (-5925 3450);
DISPLAY BOTH (-5925 3450);
FORCEPROP 1 LAST WATTAGE 1/16W
J 2
(-5825 3550);
DISPLAY 0.617021 (-5825 3550);
PAINT SKYBLUE (-5825 3550);
FORCEPROP 1 LASTPIN (-5925 3500) $PN 1
J 0
(-5913 3512);
DISPLAY 0.787234 (-5913 3512);
PAINT ORANGE (-5913 3512);
FORCEPROP 1 LASTPIN (-5725 3500) $PN 2
J 0
(-5763 3512);
DISPLAY 0.787234 (-5763 3512);
PAINT ORANGE (-5763 3512);
FORCEPROP 1 LAST LOCATION RF3
J 0
(-5950 3650);
DISPLAY 0.617021 (-5950 3650);
PAINT AQUA (-5950 3650);
FORCEPROP 1 LAST PART_NUMBER G85996-004
J 0
(-5950 3600);
DISPLAY 0.617021 (-5950 3600);
PAINT BLUE (-5950 3600);
FORCEPROP 1 LAST VALUE 1.0K
J 2
(-5775 3650);
DISPLAY 0.617021 (-5775 3650);
PAINT SKYBLUE (-5775 3650);
FORCEPROP 1 LAST TOLERANCE 0.1%
J 0
(-5750 3650);
DISPLAY 0.617021 (-5750 3650);
PAINT SKYBLUE (-5750 3650);
FORCEPROP 2 LAST CDS_LIB mstr_discrete
J 0
(-5825 3500);
PAINT MONO (-5825 3500);
DISPLAY INVISIBLE (-5825 3500);
FORCEPROP 1 LAST PATH I184
J 0
(-5875 3650);
DISPLAY 0.978723 (-5875 3650);
PAINT WHITE (-5875 3650);
DISPLAY INVISIBLE (-5875 3650);
FORCEPROP 0 LAST ROOM SB
J 0
(-5775 3725);
DISPLAY 1.021277 (-5775 3725);
PAINT ORANGE (-5775 3725);
DISPLAY INVISIBLE (-5775 3725);
FORCEPROP 0 LAST SEC 1
J 0
(-5750 3650);
DISPLAY 0.680851 (-5750 3650);
PAINT MONO (-5750 3650);
DISPLAY INVISIBLE (-5750 3650);
FORCEPROP 2 LAST SEC_TYPE 0402
J 0
(-5875 3700);
DISPLAY 1.021277 (-5875 3700);
PAINT ORANGE (-5875 3700);
DISPLAY INVISIBLE (-5875 3700);
FORCEADD RES..1
(-5425 3500);
FORCEPROP 0 LAST FAIR_SS 064.9530D.M001
J 0
(-5500 3400);
DISPLAY 0.638298 (-5500 3400);
PAINT BROWN (-5500 3400);
DISPLAY BOTH (-5500 3400);
FORCEPROP 1 LAST LOCATION RF4
J 0
(-5550 3650);
DISPLAY 0.617021 (-5550 3650);
PAINT AQUA (-5550 3650);
FORCEPROP 1 LAST VALUE 1.0K
J 2
(-5375 3650);
DISPLAY 0.617021 (-5375 3650);
PAINT SKYBLUE (-5375 3650);
FORCEPROP 1 LAST PART_NUMBER G85996-004
J 0
(-5550 3600);
DISPLAY 0.617021 (-5550 3600);
PAINT BLUE (-5550 3600);
FORCEPROP 1 LAST PACK_TYPE 0402
J 0
(-5325 3600);
DISPLAY 0.617021 (-5325 3600);
PAINT SKYBLUE (-5325 3600);
FORCEPROP 1 LAST TOLERANCE 0.1%
J 0
(-5350 3650);
DISPLAY 0.617021 (-5350 3650);
PAINT SKYBLUE (-5350 3650);
FORCEPROP 1 LASTPIN (-5525 3500) $PN 1
J 0
(-5513 3512);
DISPLAY 0.787234 (-5513 3512);
PAINT ORANGE (-5513 3512);
FORCEPROP 1 LASTPIN (-5325 3500) $PN 2
J 0
(-5363 3512);
DISPLAY 0.787234 (-5363 3512);
PAINT ORANGE (-5363 3512);
FORCEPROP 0 LAST GROUP POWER_FAIR
J 0
(-5525 3450);
DISPLAY 0.638298 (-5525 3450);
PAINT BROWN (-5525 3450);
DISPLAY BOTH (-5525 3450);
FORCEPROP 1 LAST MATERIAL CHIP
J 0
(-5400 3550);
DISPLAY 0.617021 (-5400 3550);
PAINT SKYBLUE (-5400 3550);
FORCEPROP 1 LAST WATTAGE 1/16W
J 2
(-5425 3550);
DISPLAY 0.617021 (-5425 3550);
PAINT SKYBLUE (-5425 3550);
FORCEPROP 2 LAST CDS_LIB mstr_discrete
J 0
(-5425 3500);
PAINT MONO (-5425 3500);
DISPLAY INVISIBLE (-5425 3500);
FORCEPROP 1 LAST PATH I185
J 0
(-5475 3650);
DISPLAY 0.978723 (-5475 3650);
PAINT WHITE (-5475 3650);
DISPLAY INVISIBLE (-5475 3650);
FORCEPROP 0 LAST ROOM SB
J 0
(-5375 3725);
DISPLAY 1.021277 (-5375 3725);
PAINT ORANGE (-5375 3725);
DISPLAY INVISIBLE (-5375 3725);
FORCEPROP 0 LAST SEC 1
J 0
(-5350 3650);
DISPLAY 0.680851 (-5350 3650);
PAINT MONO (-5350 3650);
DISPLAY INVISIBLE (-5350 3650);
FORCEPROP 2 LAST SEC_TYPE 0402
J 0
(-5475 3700);
DISPLAY 1.021277 (-5475 3700);
PAINT ORANGE (-5475 3700);
DISPLAY INVISIBLE (-5475 3700);
FORCEADD RES..1
(-5025 3500);
FORCEPROP 1 LAST LOCATION RF5
J 0
(-5175 3650);
DISPLAY 0.617021 (-5175 3650);
PAINT AQUA (-5175 3650);
FORCEPROP 1 LASTPIN (-5125 3500) $PN 1
J 0
(-5113 3512);
DISPLAY 0.787234 (-5113 3512);
PAINT ORANGE (-5113 3512);
FORCEPROP 1 LASTPIN (-4925 3500) $PN 2
J 0
(-4963 3512);
DISPLAY 0.787234 (-4963 3512);
PAINT ORANGE (-4963 3512);
FORCEPROP 1 LAST PART_NUMBER G85996-004
J 0
(-5175 3600);
DISPLAY 0.617021 (-5175 3600);
PAINT BLUE (-5175 3600);
FORCEPROP 1 LAST VALUE 1.0K
J 2
(-5000 3650);
DISPLAY 0.617021 (-5000 3650);
PAINT SKYBLUE (-5000 3650);
FORCEPROP 1 LAST WATTAGE 1/16W
J 2
(-5050 3550);
DISPLAY 0.617021 (-5050 3550);
PAINT SKYBLUE (-5050 3550);
FORCEPROP 0 LAST GROUP POWER_FAIR
J 0
(-5125 3450);
DISPLAY 0.638298 (-5125 3450);
PAINT BROWN (-5125 3450);
DISPLAY BOTH (-5125 3450);
FORCEPROP 0 LAST FAIR_SS 064.9530D.M001
J 0
(-5050 3400);
DISPLAY 0.638298 (-5050 3400);
PAINT BROWN (-5050 3400);
DISPLAY BOTH (-5050 3400);
FORCEPROP 1 LAST MATERIAL CHIP
J 0
(-5000 3550);
DISPLAY 0.617021 (-5000 3550);
PAINT SKYBLUE (-5000 3550);
FORCEPROP 1 LAST PACK_TYPE 0402
J 0
(-4950 3600);
DISPLAY 0.617021 (-4950 3600);
PAINT SKYBLUE (-4950 3600);
FORCEPROP 1 LAST TOLERANCE 0.1%
J 0
(-4975 3650);
DISPLAY 0.617021 (-4975 3650);
PAINT SKYBLUE (-4975 3650);
FORCEPROP 0 LAST ROOM SB
J 0
(-4975 3725);
DISPLAY 1.021277 (-4975 3725);
PAINT ORANGE (-4975 3725);
DISPLAY INVISIBLE (-4975 3725);
FORCEPROP 1 LAST PATH I186
J 0
(-5075 3650);
DISPLAY 0.978723 (-5075 3650);
PAINT WHITE (-5075 3650);
DISPLAY INVISIBLE (-5075 3650);
FORCEPROP 2 LAST CDS_LIB mstr_discrete
J 0
(-5025 3500);
PAINT MONO (-5025 3500);
DISPLAY INVISIBLE (-5025 3500);
FORCEPROP 0 LAST SEC 1
J 0
(-4950 3650);
DISPLAY 0.680851 (-4950 3650);
PAINT MONO (-4950 3650);
DISPLAY INVISIBLE (-4950 3650);
FORCEPROP 2 LAST SEC_TYPE 0402
J 0
(-5075 3700);
DISPLAY 1.021277 (-5075 3700);
PAINT ORANGE (-5075 3700);
DISPLAY INVISIBLE (-5075 3700);
FORCEADD RES..2
R 2
(-1925 4100);
FORCEPROP 1 LAST MATERIAL CHIP
J 2
(-1765 4050);
DISPLAY 0.617021 (-1765 4050);
PAINT SKYBLUE (-1765 4050);
FORCEPROP 1 LAST WATTAGE 1/16W
J 2
(-1740 4100);
DISPLAY 0.617021 (-1740 4100);
PAINT SKYBLUE (-1740 4100);
FORCEPROP 1 LASTPIN (-1925 4200) $PN 1
J 2
(-1930 4162);
DISPLAY 0.617021 (-1930 4162);
PAINT ORANGE (-1930 4162);
FORCEPROP 1 LAST TOLERANCE 1%
J 2
(-1795 4150);
DISPLAY 0.617021 (-1795 4150);
PAINT SKYBLUE (-1795 4150);
FORCEPROP 1 LAST LOCATION R4E4
J 2
(-1770 4250);
DISPLAY 0.617021 (-1770 4250);
PAINT AQUA (-1770 4250);
FORCEPROP 1 LAST VALUE 1.00K
J 2
(-1770 4200);
DISPLAY 0.617021 (-1770 4200);
PAINT SKYBLUE (-1770 4200);
FORCEPROP 1 LAST PACK_TYPE 0402
J 2
(-1765 3950);
DISPLAY 0.617021 (-1765 3950);
PAINT SKYBLUE (-1765 3950);
FORCEPROP 1 LASTPIN (-1925 4000) $PN 2
J 2
(-1930 4010);
DISPLAY 0.617021 (-1930 4010);
PAINT ORANGE (-1930 4010);
FORCEPROP 1 LAST PART_NUMBER G21796-026
J 2
(-1665 4000);
DISPLAY 0.617021 (-1665 4000);
PAINT BLUE (-1665 4000);
FORCEPROP 2 LAST ROOM PVCCIN_CPU0_VR
J 0
(-1950 4275);
DISPLAY 1.361702 (-1950 4275);
PAINT ORANGE (-1950 4275);
DISPLAY INVISIBLE (-1950 4275);
FORCEPROP 2 LAST SEC 1
J 0
(-1975 4325);
DISPLAY 0.680851 (-1975 4325);
PAINT MONO (-1975 4325);
DISPLAY INVISIBLE (-1975 4325);
FORCEPROP 2 LAST SEC_TYPE 0402
J 0
(-1975 4325);
DISPLAY 1.021277 (-1975 4325);
PAINT ORANGE (-1975 4325);
DISPLAY INVISIBLE (-1975 4325);
FORCEPROP 2 LAST CDS_LIB mstr_discrete
J 2
(-1925 4100);
PAINT ORANGE (-1925 4100);
DISPLAY INVISIBLE (-1925 4100);
FORCEPROP 1 LAST PATH I187
J 2
(-1975 4275);
DISPLAY 0.978723 (-1975 4275);
PAINT WHITE (-1975 4275);
DISPLAY INVISIBLE (-1975 4275);
FORCEPROP 2 LAST CDS_LOCATION R4E4
J 2
(-1970 4225);
DISPLAY 0.617021 (-1970 4225);
PAINT AQUA (-1970 4225);
DISPLAY INVISIBLE (-1970 4225);
FORCEADD RES..2
(-5650 4275);
FORCEPROP 1 LAST VALUE 49.9
J 0
(-5605 4350);
DISPLAY 0.617021 (-5605 4350);
PAINT SKYBLUE (-5605 4350);
FORCEPROP 1 LAST TOLERANCE 1%
J 0
(-5605 4300);
DISPLAY 0.617021 (-5605 4300);
PAINT SKYBLUE (-5605 4300);
FORCEPROP 1 LASTPIN (-5650 4175) $PN 2
J 0
(-5645 4185);
DISPLAY 0.617021 (-5645 4185);
PAINT ORANGE (-5645 4185);
FORCEPROP 1 LAST MATERIAL EMPTY
J 0
(-5610 4200);
DISPLAY 0.617021 (-5610 4200);
PAINT RED (-5610 4200);
FORCEPROP 1 LASTPIN (-5650 4375) $PN 1
J 0
(-5645 4337);
DISPLAY 0.617021 (-5645 4337);
PAINT ORANGE (-5645 4337);
FORCEPROP 1 LAST LOCATION R4E9
J 0
(-5605 4400);
DISPLAY 0.617021 (-5605 4400);
PAINT AQUA (-5605 4400);
FORCEPROP 1 LAST PART_NUMBER G21796-047
J 0
(-5610 4150);
DISPLAY 0.617021 (-5610 4150);
PAINT BLUE (-5610 4150);
FORCEPROP 1 LAST PACK_TYPE 0402
J 0
(-5610 4100);
DISPLAY 0.617021 (-5610 4100);
PAINT SKYBLUE (-5610 4100);
FORCEPROP 1 LAST WATTAGE 1/16W
J 0
(-5610 4250);
DISPLAY 0.617021 (-5610 4250);
PAINT SKYBLUE (-5610 4250);
FORCEPROP 2 LAST CDS_LOCATION R4E9
J 0
(-5605 4400);
DISPLAY 0.617021 (-5605 4400);
PAINT AQUA (-5605 4400);
DISPLAY INVISIBLE (-5605 4400);
FORCEPROP 0 LAST CDS_SEC 1
J 0
(-5600 4450);
PAINT MONO (-5600 4450);
DISPLAY INVISIBLE (-5600 4450);
FORCEPROP 2 LAST SEC 1
J 0
(-5600 4525);
PAINT MONO (-5600 4525);
DISPLAY INVISIBLE (-5600 4525);
FORCEPROP 2 LAST SEC_TYPE 0402
J 0
(-5600 4525);
DISPLAY 1.021277 (-5600 4525);
PAINT ORANGE (-5600 4525);
DISPLAY INVISIBLE (-5600 4525);
FORCEPROP 2 LAST ROOM PVCCIO_CPU0
J 0
(-5600 4450);
DISPLAY 1.361702 (-5600 4450);
PAINT ORANGE (-5600 4450);
DISPLAY INVISIBLE (-5600 4450);
FORCEPROP 2 LAST CDS_LIB mstr_discrete
J 0
(-5650 4275);
PAINT ORANGE (-5650 4275);
DISPLAY INVISIBLE (-5650 4275);
FORCEPROP 1 LAST PATH I189
J 0
(-5600 4450);
DISPLAY 0.978723 (-5600 4450);
PAINT WHITE (-5600 4450);
DISPLAY INVISIBLE (-5600 4450);
FORCEADD RES..2
(-1275 3750);
FORCEPROP 1 LAST WATTAGE 1/16W
J 0
(-1235 3725);
DISPLAY 0.617021 (-1235 3725);
PAINT SKYBLUE (-1235 3725);
FORCEPROP 1 LAST MATERIAL EMPTY
J 0
(-1235 3675);
DISPLAY 0.617021 (-1235 3675);
PAINT RED (-1235 3675);
FORCEPROP 1 LAST PART_NUMBER G21796-017
J 0
(-1235 3625);
DISPLAY 0.617021 (-1235 3625);
PAINT BLUE (-1235 3625);
FORCEPROP 1 LAST PACK_TYPE 0402
J 0
(-1235 3575);
DISPLAY 0.617021 (-1235 3575);
PAINT SKYBLUE (-1235 3575);
FORCEPROP 1 LAST LOCATION R4E10
J 0
(-1230 3875);
DISPLAY 0.617021 (-1230 3875);
PAINT AQUA (-1230 3875);
FORCEPROP 1 LAST VALUE 100.0
J 0
(-1230 3825);
DISPLAY 0.617021 (-1230 3825);
PAINT SKYBLUE (-1230 3825);
FORCEPROP 1 LAST TOLERANCE 1%
J 0
(-1230 3775);
DISPLAY 0.617021 (-1230 3775);
PAINT SKYBLUE (-1230 3775);
FORCEPROP 1 LASTPIN (-1275 3650) $PN 2
J 0
(-1270 3660);
DISPLAY 0.617021 (-1270 3660);
PAINT ORANGE (-1270 3660);
FORCEPROP 1 LASTPIN (-1275 3850) $PN 1
J 0
(-1270 3812);
DISPLAY 0.617021 (-1270 3812);
PAINT ORANGE (-1270 3812);
FORCEPROP 2 LAST CDS_LOCATION R4E10
J 0
(-1230 3875);
DISPLAY 0.617021 (-1230 3875);
PAINT AQUA (-1230 3875);
DISPLAY INVISIBLE (-1230 3875);
FORCEPROP 1 LAST PATH I190
J 0
(-1225 3925);
DISPLAY 0.978723 (-1225 3925);
PAINT WHITE (-1225 3925);
DISPLAY INVISIBLE (-1225 3925);
FORCEPROP 0 LAST CDS_SEC 1
J 0
(-1225 3925);
PAINT MONO (-1225 3925);
DISPLAY INVISIBLE (-1225 3925);
FORCEPROP 2 LAST SEC_TYPE 0402
J 0
(-1225 3975);
DISPLAY 1.021277 (-1225 3975);
PAINT ORANGE (-1225 3975);
DISPLAY INVISIBLE (-1225 3975);
FORCEPROP 0 LAST SEC 1
J 0
(-1225 3925);
DISPLAY 0.680851 (-1225 3925);
PAINT MONO (-1225 3925);
DISPLAY INVISIBLE (-1225 3925);
FORCEPROP 2 LAST ROOM PVCCIO_CPU0
J 0
(-1225 3925);
DISPLAY 1.361702 (-1225 3925);
PAINT ORANGE (-1225 3925);
DISPLAY INVISIBLE (-1225 3925);
FORCEPROP 2 LAST CDS_LIB mstr_discrete
J 0
(-1275 3750);
PAINT ORANGE (-1275 3750);
DISPLAY INVISIBLE (-1275 3750);
FORCEADD PIN-CON3-27-GP..1
R 2
(-3225 850);
FORCEPROP 1 LAST LOCATION J8D4
J 2
(-3175 985);
DISPLAY 0.617021 (-3175 985);
PAINT GREEN (-3175 985);
FORCEPROP 1 LAST VALUE PIN-CON3-27-GP
J 2
(-3075 690);
DISPLAY 0.617021 (-3075 690);
PAINT GREEN (-3075 690);
FORCEPROP 2 LASTPIN (-3025 925) $PN 1
J 0
(-3015 935);
DISPLAY 0.808511 (-3015 935);
PAINT ORANGE (-3015 935);
FORCEPROP 2 LASTPIN (-3025 825) $PN 2
J 0
(-3015 835);
DISPLAY 0.808511 (-3015 835);
PAINT ORANGE (-3015 835);
FORCEPROP 2 LASTPIN (-3025 775) $PN 3
J 0
(-3015 785);
DISPLAY 0.808511 (-3015 785);
PAINT ORANGE (-3015 785);
FORCEPROP 1 LAST CDS_LMAN_SYM_OUTLINE -50,125,50,-125
J 2
(-3225 850);
DISPLAY 0.468085 (-3225 850);
PAINT GREEN (-3225 850);
DISPLAY INVISIBLE (-3225 850);
FORCEPROP 1 LAST PATH I191
J 2
(-3225 890);
DISPLAY 0.617021 (-3225 890);
PAINT GREEN (-3225 890);
DISPLAY INVISIBLE (-3225 890);
FORCEPROP 2 LAST CDS_LIB w_hdl
J 2
(-3225 850);
PAINT MONO (-3225 850);
DISPLAY INVISIBLE (-3225 850);
FORCEPROP 1 LAST PART_NUMBER 021.60545.0103
J 2
(-3225 810);
DISPLAY 0.617021 (-3225 810);
PAINT GREEN (-3225 810);
DISPLAY INVISIBLE (-3225 810);
FORCEPROP 2 LAST SEC_TYPE CONN-G7
J 2
(-3175 1025);
DISPLAY 1.021277 (-3175 1025);
PAINT ORANGE (-3175 1025);
DISPLAY INVISIBLE (-3175 1025);
FORCEPROP 2 LAST SEC 1
J 2
(-3175 1025);
DISPLAY 0.680851 (-3175 1025);
PAINT MONO (-3175 1025);
DISPLAY INVISIBLE (-3175 1025);
FORCEPROP 1 LAST PACK_TYPE CONN-G7
J 2
(-3225 850);
DISPLAY 0.617021 (-3225 850);
PAINT GREEN (-3225 850);
DISPLAY INVISIBLE (-3225 850);
FORCEADD CAP_A..1
(-6600 4200);
FORCEPROP 1 LASTPIN (-6600 4100) $PN 2
J 0
(-6590 4080);
DISPLAY 0.787234 (-6590 4080);
PAINT ORANGE (-6590 4080);
FORCEPROP 1 LAST VOLTAGE 16V
J 0
(-6550 4250);
DISPLAY 0.617021 (-6550 4250);
PAINT SKYBLUE (-6550 4250);
FORCEPROP 1 LAST TOLERANCE 10%
J 0
(-6550 4200);
DISPLAY 0.617021 (-6550 4200);
PAINT SKYBLUE (-6550 4200);
FORCEPROP 1 LAST MATERIAL X7R
J 0
(-6550 4150);
DISPLAY 0.617021 (-6550 4150);
PAINT SKYBLUE (-6550 4150);
FORCEPROP 1 LAST PACK_TYPE 0402V
J 0
(-6550 4050);
DISPLAY 0.617021 (-6550 4050);
PAINT SKYBLUE (-6550 4050);
FORCEPROP 1 LASTPIN (-6600 4300) $PN 1
J 0
(-6590 4280);
DISPLAY 0.787234 (-6590 4280);
PAINT ORANGE (-6590 4280);
FORCEPROP 1 LAST LOCATION C4D20
J 0
(-6550 4350);
DISPLAY 0.617021 (-6550 4350);
PAINT AQUA (-6550 4350);
FORCEPROP 1 LAST VALUE 0.1UF
J 0
(-6550 4300);
DISPLAY 0.617021 (-6550 4300);
PAINT SKYBLUE (-6550 4300);
FORCEPROP 1 LAST PART_NUMBER A36096-030
J 0
(-6550 4100);
DISPLAY 0.617021 (-6550 4100);
PAINT BLUE (-6550 4100);
FORCEPROP 1 LAST PATH I192
J 0
(-6550 4350);
DISPLAY 0.978723 (-6550 4350);
PAINT WHITE (-6550 4350);
DISPLAY INVISIBLE (-6550 4350);
FORCEPROP 0 LAST CDS_SEC 1
J 0
(-6550 4350);
PAINT MONO (-6550 4350);
DISPLAY INVISIBLE (-6550 4350);
FORCEPROP 2 LAST SEC 1
J 0
(-6550 4400);
DISPLAY 0.680851 (-6550 4400);
PAINT MONO (-6550 4400);
DISPLAY INVISIBLE (-6550 4400);
FORCEPROP 2 LAST SEC_TYPE 0402V
J 0
(-6550 4400);
DISPLAY 1.021277 (-6550 4400);
PAINT ORANGE (-6550 4400);
DISPLAY INVISIBLE (-6550 4400);
FORCEPROP 0 LAST ROOM CPU_FANS
J 0
(-6550 4400);
DISPLAY 1.021277 (-6550 4400);
PAINT ORANGE (-6550 4400);
DISPLAY INVISIBLE (-6550 4400);
FORCEPROP 0 LAST BOM_COST SM_THERM
J 0
(-6550 4350);
DISPLAY 1.021277 (-6550 4350);
PAINT ORANGE (-6550 4350);
DISPLAY INVISIBLE (-6550 4350);
FORCEPROP 2 LAST CDS_LIB dev_discrete
J 0
(-6600 4200);
PAINT MONO (-6600 4200);
DISPLAY INVISIBLE (-6600 4200);
FORCEPROP 0 LAST CDS_LOCATION C4D20
J 0
(-6550 4350);
PAINT MONO (-6550 4350);
DISPLAY INVISIBLE (-6550 4350);
FORCEADD OFFPAGE..2
(-1050 2975);
FORCEPROP 2 LAST $XR1 145 
J 0
(-771 2975);
DISPLAY 0.638298 (-771 2975);
PAINT MONO (-771 2975);
FORCEPROP 2 LAST $XR0 95 
J 0
(-861 2975);
DISPLAY 0.638298 (-861 2975);
PAINT MONO (-861 2975);
FORCEPROP 2 LAST CDS_LIB mstr_standard
J 0
(-1050 2975);
PAINT ORANGE (-1050 2975);
DISPLAY INVISIBLE (-1050 2975);
FORCEPROP 2 LAST ROOM PVCCIN_CPU0_VR
J 0
(-1475 3050);
DISPLAY 1.361702 (-1475 3050);
PAINT ORANGE (-1475 3050);
DISPLAY INVISIBLE (-1475 3050);
FORCEPROP 2 LAST PATH I2
J 0
(-875 3050);
DISPLAY 1.021277 (-875 3050);
PAINT ORANGE (-875 3050);
DISPLAY INVISIBLE (-875 3050);
FORCEPROP 1 LAST OFFPAGE TRUE
J 0
(-725 2850);
DISPLAY 1.170213 (-725 2850);
PAINT GREEN (-725 2850);
DISPLAY INVISIBLE (-725 2850);
FORCEPROP 1 LAST COMMENT_BODY TRUE
J 0
(-1095 2880);
DISPLAY 1.170213 (-1095 2880);
PAINT GREEN (-1095 2880);
DISPLAY INVISIBLE (-1095 2880);
FORCEADD RES..2
(-2075 3750);
FORCEPROP 1 LAST PACK_TYPE 0402
J 0
(-2035 3575);
DISPLAY 0.617021 (-2035 3575);
PAINT SKYBLUE (-2035 3575);
FORCEPROP 1 LAST PART_NUMBER G21796-311
J 0
(-2035 3625);
DISPLAY 0.617021 (-2035 3625);
PAINT BLUE (-2035 3625);
FORCEPROP 1 LAST WATTAGE 1/16W
J 0
(-2035 3725);
DISPLAY 0.723404 (-2035 3725);
PAINT SKYBLUE (-2035 3725);
FORCEPROP 1 LAST TOLERANCE 1.0%
J 0
(-2030 3775);
DISPLAY 0.617021 (-2030 3775);
PAINT SKYBLUE (-2030 3775);
FORCEPROP 1 LAST VALUE 2.26K
J 0
(-2030 3825);
DISPLAY 0.617021 (-2030 3825);
PAINT SKYBLUE (-2030 3825);
FORCEPROP 1 LASTPIN (-2075 3650) $PN 2
J 0
(-2070 3660);
DISPLAY 0.617021 (-2070 3660);
PAINT ORANGE (-2070 3660);
FORCEPROP 1 LAST LOCATION R4D31
J 0
(-2030 3875);
DISPLAY 0.617021 (-2030 3875);
PAINT AQUA (-2030 3875);
FORCEPROP 1 LASTPIN (-2075 3850) $PN 1
J 0
(-2070 3812);
DISPLAY 0.617021 (-2070 3812);
PAINT ORANGE (-2070 3812);
FORCEPROP 1 LAST MATERIAL EMPTY
R 1
J 0
(-2185 3675);
DISPLAY 0.617021 (-2185 3675);
PAINT RED (-2185 3675);
FORCEPROP 2 LAST CDS_LIB mstr_discrete
J 0
(-2075 3750);
PAINT ORANGE (-2075 3750);
DISPLAY INVISIBLE (-2075 3750);
FORCEPROP 2 LAST ROOM PVCCIN_CPU0_VR
J 0
(-2025 3725);
DISPLAY 1.361702 (-2025 3725);
PAINT ORANGE (-2025 3725);
DISPLAY INVISIBLE (-2025 3725);
FORCEPROP 1 LAST PATH I22
J 0
(-2025 3925);
DISPLAY 0.978723 (-2025 3925);
PAINT WHITE (-2025 3925);
DISPLAY INVISIBLE (-2025 3925);
FORCEPROP 2 LAST CDS_LOCATION R4D31
J 0
(-2030 3875);
DISPLAY 0.617021 (-2030 3875);
PAINT AQUA (-2030 3875);
DISPLAY INVISIBLE (-2030 3875);
FORCEPROP 2 LAST SEC 1
J 0
(-2025 3975);
DISPLAY 0.680851 (-2025 3975);
PAINT MONO (-2025 3975);
DISPLAY INVISIBLE (-2025 3975);
FORCEPROP 2 LAST SEC_TYPE 0402
J 0
(-2025 3975);
DISPLAY 1.021277 (-2025 3975);
PAINT ORANGE (-2025 3975);
DISPLAY INVISIBLE (-2025 3975);
FORCEADD RES..2
(-2500 3925);
FORCEPROP 1 LAST PACK_TYPE 0402
J 0
(-2460 3750);
DISPLAY 0.617021 (-2460 3750);
PAINT SKYBLUE (-2460 3750);
FORCEPROP 1 LAST PART_NUMBER G21796-026
J 0
(-2460 3800);
DISPLAY 0.617021 (-2460 3800);
PAINT BLUE (-2460 3800);
FORCEPROP 1 LAST MATERIAL CHIP
J 0
(-2460 3850);
DISPLAY 0.617021 (-2460 3850);
PAINT SKYBLUE (-2460 3850);
FORCEPROP 1 LAST TOLERANCE 1%
J 0
(-2455 3950);
DISPLAY 0.617021 (-2455 3950);
PAINT SKYBLUE (-2455 3950);
FORCEPROP 1 LAST VALUE 1.00K
J 0
(-2455 4000);
DISPLAY 0.617021 (-2455 4000);
PAINT SKYBLUE (-2455 4000);
FORCEPROP 1 LAST LOCATION R4D58
J 0
(-2455 4050);
DISPLAY 0.617021 (-2455 4050);
PAINT AQUA (-2455 4050);
FORCEPROP 1 LASTPIN (-2500 3825) $PN 2
J 0
(-2495 3835);
DISPLAY 0.617021 (-2495 3835);
PAINT ORANGE (-2495 3835);
FORCEPROP 1 LASTPIN (-2500 4025) $PN 1
J 0
(-2495 3987);
DISPLAY 0.617021 (-2495 3987);
PAINT ORANGE (-2495 3987);
FORCEPROP 1 LAST WATTAGE 1/16W
J 0
(-2460 3900);
DISPLAY 0.617021 (-2460 3900);
PAINT SKYBLUE (-2460 3900);
FORCEPROP 2 LAST CDS_LOCATION R4D58
J 0
(-2455 4050);
DISPLAY 0.617021 (-2455 4050);
PAINT AQUA (-2455 4050);
DISPLAY INVISIBLE (-2455 4050);
FORCEPROP 2 LAST CDS_LIB mstr_discrete
J 2
(-2500 3925);
PAINT ORANGE (-2500 3925);
DISPLAY INVISIBLE (-2500 3925);
FORCEPROP 2 LAST ROOM PVCCIN_CPU0_VR
J 0
(-2450 4100);
DISPLAY 1.361702 (-2450 4100);
PAINT ORANGE (-2450 4100);
DISPLAY INVISIBLE (-2450 4100);
FORCEPROP 1 LAST PATH I25
J 0
(-2450 4100);
DISPLAY 0.978723 (-2450 4100);
PAINT WHITE (-2450 4100);
DISPLAY INVISIBLE (-2450 4100);
FORCEPROP 2 LAST SEC 1
J 0
(-2450 4150);
DISPLAY 0.680851 (-2450 4150);
PAINT MONO (-2450 4150);
DISPLAY INVISIBLE (-2450 4150);
FORCEPROP 2 LAST SEC_TYPE 0402
J 0
(-2450 4150);
DISPLAY 1.021277 (-2450 4150);
PAINT ORANGE (-2450 4150);
DISPLAY INVISIBLE (-2450 4150);
FORCEADD RES..1
(-2025 2875);
FORCEPROP 1 LAST MATERIAL CHIP
J 0
(-1950 2825);
DISPLAY 0.617021 (-1950 2825);
PAINT SKYBLUE (-1950 2825);
FORCEPROP 1 LAST PART_NUMBER G21497-005
J 0
(-2175 2775);
DISPLAY 0.617021 (-2175 2775);
PAINT BLUE (-2175 2775);
FORCEPROP 1 LAST TOLERANCE 5%
J 0
(-2100 2725);
DISPLAY 0.617021 (-2100 2725);
PAINT SKYBLUE (-2100 2725);
FORCEPROP 1 LAST PACK_TYPE 0402
J 0
(-2000 2725);
DISPLAY 0.617021 (-2000 2725);
PAINT SKYBLUE (-2000 2725);
FORCEPROP 1 LAST VALUE 0.0
J 2
(-2150 2725);
DISPLAY 0.617021 (-2150 2725);
PAINT SKYBLUE (-2150 2725);
FORCEPROP 1 LAST WATTAGE 1/16W
J 2
(-2050 2675);
DISPLAY 0.617021 (-2050 2675);
PAINT SKYBLUE (-2050 2675);
FORCEPROP 1 LASTPIN (-1925 2875) $PN 2
J 0
(-1963 2887);
DISPLAY 0.617021 (-1963 2887);
PAINT ORANGE (-1963 2887);
FORCEPROP 1 LASTPIN (-2125 2875) $PN 1
J 0
(-2113 2887);
DISPLAY 0.617021 (-2113 2887);
PAINT ORANGE (-2113 2887);
FORCEPROP 1 LAST LOCATION R4D67
J 0
(-2075 2925);
DISPLAY 0.617021 (-2075 2925);
PAINT AQUA (-2075 2925);
FORCEPROP 2 LAST ROOM PVCCIN_CPU0_VR
J 0
(-2075 2975);
DISPLAY 1.361702 (-2075 2975);
PAINT ORANGE (-2075 2975);
DISPLAY INVISIBLE (-2075 2975);
FORCEPROP 1 LAST PATH I26
J 0
(-2075 3025);
DISPLAY 0.978723 (-2075 3025);
PAINT WHITE (-2075 3025);
DISPLAY INVISIBLE (-2075 3025);
FORCEPROP 2 LAST CDS_LOCATION R4D67
J 0
(-2075 2925);
DISPLAY 0.617021 (-2075 2925);
PAINT AQUA (-2075 2925);
DISPLAY INVISIBLE (-2075 2925);
FORCEPROP 2 LAST SEC 1
J 0
(-2075 3075);
DISPLAY 0.680851 (-2075 3075);
PAINT MONO (-2075 3075);
DISPLAY INVISIBLE (-2075 3075);
FORCEPROP 2 LAST SEC_TYPE 0402
J 0
(-2075 3075);
DISPLAY 1.021277 (-2075 3075);
PAINT ORANGE (-2075 3075);
DISPLAY INVISIBLE (-2075 3075);
FORCEPROP 2 LAST CDS_LIB mstr_discrete
J 0
(-2025 2875);
PAINT ORANGE (-2025 2875);
DISPLAY INVISIBLE (-2025 2875);
FORCEADD RES..2
R 2
(-2775 3925);
FORCEPROP 1 LASTPIN (-2775 3825) $PN 2
J 2
(-2780 3835);
DISPLAY 0.617021 (-2780 3835);
PAINT ORANGE (-2780 3835);
FORCEPROP 1 LAST LOCATION R4E5
J 2
(-2820 4050);
DISPLAY 0.617021 (-2820 4050);
PAINT AQUA (-2820 4050);
FORCEPROP 1 LAST PACK_TYPE 0402
J 2
(-2815 3750);
DISPLAY 0.617021 (-2815 3750);
PAINT SKYBLUE (-2815 3750);
FORCEPROP 1 LAST WATTAGE 1/16W
J 2
(-2815 3900);
DISPLAY 0.617021 (-2815 3900);
PAINT SKYBLUE (-2815 3900);
FORCEPROP 1 LAST MATERIAL CHIP
J 2
(-2815 3850);
DISPLAY 0.617021 (-2815 3850);
PAINT SKYBLUE (-2815 3850);
FORCEPROP 1 LAST PART_NUMBER G21796-026
J 2
(-2815 3800);
DISPLAY 0.617021 (-2815 3800);
PAINT BLUE (-2815 3800);
FORCEPROP 1 LAST VALUE 1.00K
J 2
(-2820 4000);
DISPLAY 0.617021 (-2820 4000);
PAINT SKYBLUE (-2820 4000);
FORCEPROP 1 LAST TOLERANCE 1%
J 2
(-2820 3950);
DISPLAY 0.617021 (-2820 3950);
PAINT SKYBLUE (-2820 3950);
FORCEPROP 1 LASTPIN (-2775 4025) $PN 1
J 2
(-2780 3987);
DISPLAY 0.617021 (-2780 3987);
PAINT ORANGE (-2780 3987);
FORCEPROP 1 LAST PATH I27
J 2
(-2825 4100);
DISPLAY 0.978723 (-2825 4100);
PAINT WHITE (-2825 4100);
DISPLAY INVISIBLE (-2825 4100);
FORCEPROP 2 LAST ROOM PVCCIN_CPU0_VR
J 0
(-2800 4100);
DISPLAY 1.361702 (-2800 4100);
PAINT ORANGE (-2800 4100);
DISPLAY INVISIBLE (-2800 4100);
FORCEPROP 2 LAST SEC 1
J 0
(-2825 4150);
DISPLAY 0.680851 (-2825 4150);
PAINT MONO (-2825 4150);
DISPLAY INVISIBLE (-2825 4150);
FORCEPROP 2 LAST SEC_TYPE 0402
J 0
(-2825 4150);
DISPLAY 1.021277 (-2825 4150);
PAINT ORANGE (-2825 4150);
DISPLAY INVISIBLE (-2825 4150);
FORCEPROP 2 LAST CDS_LIB mstr_discrete
J 2
(-2775 3925);
PAINT ORANGE (-2775 3925);
DISPLAY INVISIBLE (-2775 3925);
FORCEPROP 2 LAST CDS_LOCATION R4E5
J 2
(-2820 4050);
DISPLAY 0.617021 (-2820 4050);
PAINT AQUA (-2820 4050);
DISPLAY INVISIBLE (-2820 4050);
FORCEADD GND..1
(-1475 800);
FORCEPROP 3 LASTPIN (-1475 850) SIG_NAME GND\g
J 0
(-1465 860);
DISPLAY 0.659574 (-1465 860);
PAINT MONO (-1465 860);
DISPLAY INVISIBLE (-1465 860);
FORCEPROP 1 LAST HDL_POWER GND
J 0
(-1475 950);
DISPLAY 1.170213 (-1475 950);
PAINT GREEN (-1475 950);
DISPLAY INVISIBLE (-1475 950);
FORCEPROP 1 LAST BODY_TYPE PLUMBING
J 0
(-1520 757);
DISPLAY 0.340426 (-1520 757);
PAINT GREEN (-1520 757);
DISPLAY INVISIBLE (-1520 757);
FORCEPROP 1 LAST VOLTAGE 0
J 0
(-1475 800);
PAINT SKYBLUE (-1475 800);
DISPLAY INVISIBLE (-1475 800);
FORCEPROP 1 LAST SIZE 1B
J 0
(-1400 750);
DISPLAY 1.170213 (-1400 750);
PAINT AQUA (-1400 750);
DISPLAY INVISIBLE (-1400 750);
FORCEPROP 2 LAST CDS_LIB mstr_symbols
J 0
(-1475 800);
PAINT ORANGE (-1475 800);
DISPLAY INVISIBLE (-1475 800);
FORCEPROP 1 LAST PATH I29
J 0
(-1400 800);
DISPLAY 0.872340 (-1400 800);
PAINT AQUA (-1400 800);
DISPLAY INVISIBLE (-1400 800);
FORCEPROP 2 LAST ROOM PVCCIN_CPU0_VR
J 0
(-2050 875);
DISPLAY 1.361702 (-2050 875);
PAINT ORANGE (-2050 875);
DISPLAY INVISIBLE (-2050 875);
FORCEADD OFFPAGE..2
(-1050 2875);
FORCEPROP 2 LAST $XR2 21 
J 0
(-621 2875);
DISPLAY 0.638298 (-621 2875);
PAINT MONO (-621 2875);
FORCEPROP 2 LAST $XR1 211 
J 0
(-741 2875);
DISPLAY 0.638298 (-741 2875);
PAINT MONO (-741 2875);
FORCEPROP 2 LAST $XR0 194 
J 0
(-861 2875);
DISPLAY 0.638298 (-861 2875);
PAINT MONO (-861 2875);
FORCEPROP 2 LAST ROOM PVCCIN_CPU0_VR
J 0
(-1475 2950);
DISPLAY 1.361702 (-1475 2950);
PAINT ORANGE (-1475 2950);
DISPLAY INVISIBLE (-1475 2950);
FORCEPROP 2 LAST CDS_LIB mstr_standard
J 0
(-1050 2875);
PAINT ORANGE (-1050 2875);
DISPLAY INVISIBLE (-1050 2875);
FORCEPROP 2 LAST PATH I3
J 0
(-875 2950);
DISPLAY 1.021277 (-875 2950);
PAINT ORANGE (-875 2950);
DISPLAY INVISIBLE (-875 2950);
FORCEPROP 1 LAST OFFPAGE TRUE
J 0
(-725 2750);
DISPLAY 1.170213 (-725 2750);
PAINT GREEN (-725 2750);
DISPLAY INVISIBLE (-725 2750);
FORCEPROP 1 LAST COMMENT_BODY TRUE
J 0
(-1095 2780);
DISPLAY 1.170213 (-1095 2780);
PAINT GREEN (-1095 2780);
DISPLAY INVISIBLE (-1095 2780);
FORCEADD CAP_A..1
(-1475 1000);
FORCEPROP 1 LASTPIN (-1475 900) $PN 2
J 0
(-1465 880);
DISPLAY 0.617021 (-1465 880);
PAINT ORANGE (-1465 880);
FORCEPROP 1 LASTPIN (-1475 1100) $PN 1
J 0
(-1465 1080);
DISPLAY 0.617021 (-1465 1080);
PAINT ORANGE (-1465 1080);
FORCEPROP 1 LAST LOCATION C4D25
J 0
(-1425 1100);
DISPLAY 0.617021 (-1425 1100);
PAINT AQUA (-1425 1100);
FORCEPROP 1 LAST VALUE 1.0UF
J 0
(-1425 1050);
DISPLAY 0.617021 (-1425 1050);
PAINT SKYBLUE (-1425 1050);
FORCEPROP 1 LAST VOLTAGE 6.3V
J 0
(-1425 1000);
DISPLAY 0.617021 (-1425 1000);
PAINT SKYBLUE (-1425 1000);
FORCEPROP 1 LAST TOLERANCE 10%
J 0
(-1425 950);
DISPLAY 0.617021 (-1425 950);
PAINT SKYBLUE (-1425 950);
FORCEPROP 1 LAST MATERIAL X6S
J 0
(-1425 900);
DISPLAY 0.617021 (-1425 900);
PAINT SKYBLUE (-1425 900);
FORCEPROP 1 LAST PACK_TYPE 0402V
J 0
(-1425 800);
DISPLAY 0.617021 (-1425 800);
PAINT SKYBLUE (-1425 800);
FORCEPROP 1 LAST PART_NUMBER D97712-004
J 0
(-1425 850);
DISPLAY 0.617021 (-1425 850);
PAINT BLUE (-1425 850);
FORCEPROP 2 LAST CDS_LIB dev_discrete
J 0
(-1475 1000);
PAINT ORANGE (-1475 1000);
DISPLAY INVISIBLE (-1475 1000);
FORCEPROP 2 LAST CDS_LOCATION C4D25
J 0
(-1425 1100);
DISPLAY 0.617021 (-1425 1100);
PAINT AQUA (-1425 1100);
DISPLAY INVISIBLE (-1425 1100);
FORCEPROP 2 LAST CDS_SEC 1
J 0
(-1425 1150);
PAINT ORANGE (-1425 1150);
DISPLAY INVISIBLE (-1425 1150);
FORCEPROP 1 LAST PATH I30
J 0
(-1425 1150);
DISPLAY 0.978723 (-1425 1150);
PAINT WHITE (-1425 1150);
DISPLAY INVISIBLE (-1425 1150);
FORCEPROP 2 LAST ROOM PVCCIN_CPU0_VR
J 0
(-1425 1150);
DISPLAY 1.361702 (-1425 1150);
PAINT ORANGE (-1425 1150);
DISPLAY INVISIBLE (-1425 1150);
FORCEPROP 2 LAST SEC 1
J 0
(-1425 1200);
DISPLAY 0.680851 (-1425 1200);
PAINT MONO (-1425 1200);
DISPLAY INVISIBLE (-1425 1200);
FORCEPROP 2 LAST SEC_TYPE 0402V
J 0
(-1425 1200);
DISPLAY 1.021277 (-1425 1200);
PAINT ORANGE (-1425 1200);
DISPLAY INVISIBLE (-1425 1200);
FORCEADD CAP_A..1
(-1875 1000);
FORCEPROP 1 LAST VOLTAGE 16V
J 0
(-1825 1000);
DISPLAY 0.617021 (-1825 1000);
PAINT SKYBLUE (-1825 1000);
FORCEPROP 1 LASTPIN (-1875 900) $PN 2
J 0
(-1865 880);
DISPLAY 0.617021 (-1865 880);
PAINT ORANGE (-1865 880);
FORCEPROP 1 LASTPIN (-1875 1100) $PN 1
J 0
(-1865 1080);
DISPLAY 0.617021 (-1865 1080);
PAINT ORANGE (-1865 1080);
FORCEPROP 1 LAST LOCATION C4D26
J 0
(-1825 1100);
DISPLAY 0.617021 (-1825 1100);
PAINT AQUA (-1825 1100);
FORCEPROP 1 LAST TOLERANCE 10%
J 0
(-1825 950);
DISPLAY 0.617021 (-1825 950);
PAINT SKYBLUE (-1825 950);
FORCEPROP 1 LAST MATERIAL X7R
J 0
(-1825 900);
DISPLAY 0.617021 (-1825 900);
PAINT SKYBLUE (-1825 900);
FORCEPROP 1 LAST PART_NUMBER A36096-030
J 0
(-1825 850);
DISPLAY 0.617021 (-1825 850);
PAINT BLUE (-1825 850);
FORCEPROP 1 LAST PACK_TYPE 0402V
J 0
(-1825 800);
DISPLAY 0.617021 (-1825 800);
PAINT SKYBLUE (-1825 800);
FORCEPROP 1 LAST VALUE 0.1UF
J 0
(-1825 1050);
DISPLAY 0.617021 (-1825 1050);
PAINT SKYBLUE (-1825 1050);
FORCEPROP 2 LAST CDS_LIB dev_discrete
J 0
(-1875 1000);
PAINT ORANGE (-1875 1000);
DISPLAY INVISIBLE (-1875 1000);
FORCEPROP 2 LAST SEC 1
J 0
(-1825 1200);
DISPLAY 0.680851 (-1825 1200);
PAINT MONO (-1825 1200);
DISPLAY INVISIBLE (-1825 1200);
FORCEPROP 2 LAST SEC_TYPE 0402V
J 0
(-1825 1200);
DISPLAY 1.021277 (-1825 1200);
PAINT ORANGE (-1825 1200);
DISPLAY INVISIBLE (-1825 1200);
FORCEPROP 2 LAST CDS_SEC 1
J 0
(-1825 1150);
PAINT ORANGE (-1825 1150);
DISPLAY INVISIBLE (-1825 1150);
FORCEPROP 2 LAST CDS_LOCATION C4D26
J 0
(-1825 1100);
DISPLAY 0.617021 (-1825 1100);
PAINT AQUA (-1825 1100);
DISPLAY INVISIBLE (-1825 1100);
FORCEPROP 2 LAST ROOM PVCCIN_CPU0_VR
J 0
(-1825 1150);
DISPLAY 1.361702 (-1825 1150);
PAINT ORANGE (-1825 1150);
DISPLAY INVISIBLE (-1825 1150);
FORCEPROP 1 LAST PATH I32
J 0
(-1825 1150);
DISPLAY 0.978723 (-1825 1150);
PAINT WHITE (-1825 1150);
DISPLAY INVISIBLE (-1825 1150);
FORCEADD GND..1
(-1875 800);
FORCEPROP 3 LASTPIN (-1875 850) SIG_NAME GND\g
J 0
(-1865 860);
DISPLAY 0.659574 (-1865 860);
PAINT MONO (-1865 860);
DISPLAY INVISIBLE (-1865 860);
FORCEPROP 2 LAST ROOM PVCCIN_CPU0_VR
J 0
(-2450 875);
DISPLAY 1.361702 (-2450 875);
PAINT ORANGE (-2450 875);
DISPLAY INVISIBLE (-2450 875);
FORCEPROP 1 LAST SIZE 1B
J 0
(-1800 750);
DISPLAY 1.170213 (-1800 750);
PAINT AQUA (-1800 750);
DISPLAY INVISIBLE (-1800 750);
FORCEPROP 1 LAST PATH I33
J 0
(-1800 800);
DISPLAY 0.872340 (-1800 800);
PAINT AQUA (-1800 800);
DISPLAY INVISIBLE (-1800 800);
FORCEPROP 1 LAST VOLTAGE 0
J 0
(-1875 800);
PAINT SKYBLUE (-1875 800);
DISPLAY INVISIBLE (-1875 800);
FORCEPROP 2 LAST CDS_LIB mstr_symbols
J 0
(-1875 800);
PAINT ORANGE (-1875 800);
DISPLAY INVISIBLE (-1875 800);
FORCEPROP 1 LAST BODY_TYPE PLUMBING
J 0
(-1920 757);
DISPLAY 0.340426 (-1920 757);
PAINT GREEN (-1920 757);
DISPLAY INVISIBLE (-1920 757);
FORCEPROP 1 LAST HDL_POWER GND
J 0
(-1875 950);
DISPLAY 1.170213 (-1875 950);
PAINT GREEN (-1875 950);
DISPLAY INVISIBLE (-1875 950);
FORCEADD GND..1
(-3075 1550);
FORCEPROP 3 LASTPIN (-3075 1600) SIG_NAME GND\g
J 0
(-3065 1610);
DISPLAY 0.659574 (-3065 1610);
PAINT MONO (-3065 1610);
DISPLAY INVISIBLE (-3065 1610);
FORCEPROP 2 LAST ROOM PVCCIN_CPU0_VR
J 0
(-3650 1625);
DISPLAY 1.361702 (-3650 1625);
PAINT ORANGE (-3650 1625);
DISPLAY INVISIBLE (-3650 1625);
FORCEPROP 1 LAST VOLTAGE 0
J 0
(-3075 1550);
PAINT SKYBLUE (-3075 1550);
DISPLAY INVISIBLE (-3075 1550);
FORCEPROP 2 LAST CDS_LIB mstr_symbols
J 0
(-3075 1550);
PAINT ORANGE (-3075 1550);
DISPLAY INVISIBLE (-3075 1550);
FORCEPROP 1 LAST PATH I35
J 0
(-3000 1550);
DISPLAY 0.872340 (-3000 1550);
PAINT AQUA (-3000 1550);
DISPLAY INVISIBLE (-3000 1550);
FORCEPROP 1 LAST SIZE 1B
J 0
(-3000 1500);
DISPLAY 1.170213 (-3000 1500);
PAINT AQUA (-3000 1500);
DISPLAY INVISIBLE (-3000 1500);
FORCEPROP 1 LAST BODY_TYPE PLUMBING
J 0
(-3120 1507);
DISPLAY 0.340426 (-3120 1507);
PAINT GREEN (-3120 1507);
DISPLAY INVISIBLE (-3120 1507);
FORCEPROP 1 LAST HDL_POWER GND
J 0
(-3075 1700);
DISPLAY 1.170213 (-3075 1700);
PAINT GREEN (-3075 1700);
DISPLAY INVISIBLE (-3075 1700);
FORCEADD GND..1
(-3550 3725);
FORCEPROP 3 LASTPIN (-3550 3775) SIG_NAME GND\g
J 0
(-3540 3785);
DISPLAY 0.659574 (-3540 3785);
PAINT MONO (-3540 3785);
DISPLAY INVISIBLE (-3540 3785);
FORCEPROP 2 LAST ROOM PVCCIN_CPU0_VR
J 0
(-4125 3800);
DISPLAY 1.361702 (-4125 3800);
PAINT ORANGE (-4125 3800);
DISPLAY INVISIBLE (-4125 3800);
FORCEPROP 1 LAST SIZE 1B
J 0
(-3475 3675);
DISPLAY 1.170213 (-3475 3675);
PAINT AQUA (-3475 3675);
DISPLAY INVISIBLE (-3475 3675);
FORCEPROP 1 LAST PATH I36
J 0
(-3475 3725);
DISPLAY 0.872340 (-3475 3725);
PAINT AQUA (-3475 3725);
DISPLAY INVISIBLE (-3475 3725);
FORCEPROP 2 LAST CDS_LIB mstr_symbols
J 0
(-3550 3725);
PAINT ORANGE (-3550 3725);
DISPLAY INVISIBLE (-3550 3725);
FORCEPROP 1 LAST VOLTAGE 0
J 0
(-3550 3725);
PAINT SKYBLUE (-3550 3725);
DISPLAY INVISIBLE (-3550 3725);
FORCEPROP 1 LAST BODY_TYPE PLUMBING
J 0
(-3595 3682);
DISPLAY 0.340426 (-3595 3682);
PAINT GREEN (-3595 3682);
DISPLAY INVISIBLE (-3595 3682);
FORCEPROP 1 LAST HDL_POWER GND
J 0
(-3550 3875);
DISPLAY 1.170213 (-3550 3875);
PAINT GREEN (-3550 3875);
DISPLAY INVISIBLE (-3550 3875);
FORCEADD CAP_A..1
(-3550 3925);
FORCEPROP 1 LASTPIN (-3550 3825) $PN 2
J 0
(-3540 3805);
DISPLAY 0.617021 (-3540 3805);
PAINT ORANGE (-3540 3805);
FORCEPROP 1 LASTPIN (-3550 4025) $PN 1
J 0
(-3540 4005);
DISPLAY 0.617021 (-3540 4005);
PAINT ORANGE (-3540 4005);
FORCEPROP 1 LAST VALUE 1.0UF
J 0
(-3500 3975);
DISPLAY 0.617021 (-3500 3975);
PAINT SKYBLUE (-3500 3975);
FORCEPROP 1 LAST LOCATION C4D15
J 0
(-3500 4025);
DISPLAY 0.617021 (-3500 4025);
PAINT AQUA (-3500 4025);
FORCEPROP 1 LAST TOLERANCE 10%
J 0
(-3500 3875);
DISPLAY 0.617021 (-3500 3875);
PAINT SKYBLUE (-3500 3875);
FORCEPROP 1 LAST VOLTAGE 6.3V
J 0
(-3500 3925);
DISPLAY 0.617021 (-3500 3925);
PAINT SKYBLUE (-3500 3925);
FORCEPROP 1 LAST PACK_TYPE 0402V
J 0
(-3500 3725);
DISPLAY 0.617021 (-3500 3725);
PAINT SKYBLUE (-3500 3725);
FORCEPROP 1 LAST PART_NUMBER D97712-004
J 0
(-3500 3775);
DISPLAY 0.617021 (-3500 3775);
PAINT BLUE (-3500 3775);
FORCEPROP 1 LAST MATERIAL X6S
J 0
(-3500 3825);
DISPLAY 0.617021 (-3500 3825);
PAINT SKYBLUE (-3500 3825);
FORCEPROP 2 LAST CDS_LOCATION C4D15
J 0
(-3500 4025);
DISPLAY 0.617021 (-3500 4025);
PAINT AQUA (-3500 4025);
DISPLAY INVISIBLE (-3500 4025);
FORCEPROP 2 LAST CDS_LIB dev_discrete
J 0
(-3550 3925);
PAINT ORANGE (-3550 3925);
DISPLAY INVISIBLE (-3550 3925);
FORCEPROP 2 LAST ROOM PVCCIN_CPU0_VR
J 0
(-3500 4075);
DISPLAY 1.361702 (-3500 4075);
PAINT ORANGE (-3500 4075);
DISPLAY INVISIBLE (-3500 4075);
FORCEPROP 1 LAST PATH I37
J 0
(-3500 4075);
DISPLAY 0.978723 (-3500 4075);
PAINT WHITE (-3500 4075);
DISPLAY INVISIBLE (-3500 4075);
FORCEPROP 2 LAST CDS_SEC 1
J 0
(-3500 4075);
PAINT ORANGE (-3500 4075);
DISPLAY INVISIBLE (-3500 4075);
FORCEPROP 2 LAST SEC 1
J 0
(-3500 4125);
DISPLAY 0.680851 (-3500 4125);
PAINT MONO (-3500 4125);
DISPLAY INVISIBLE (-3500 4125);
FORCEPROP 2 LAST SEC_TYPE 0402V
J 0
(-3500 4125);
DISPLAY 1.021277 (-3500 4125);
PAINT ORANGE (-3500 4125);
DISPLAY INVISIBLE (-3500 4125);
FORCEADD GND..1
(-3950 3725);
FORCEPROP 3 LASTPIN (-3950 3775) SIG_NAME GND\g
J 0
(-3940 3785);
DISPLAY 0.659574 (-3940 3785);
PAINT MONO (-3940 3785);
DISPLAY INVISIBLE (-3940 3785);
FORCEPROP 2 LAST ROOM PVCCIN_CPU0_VR
J 0
(-4525 3800);
DISPLAY 1.361702 (-4525 3800);
PAINT ORANGE (-4525 3800);
DISPLAY INVISIBLE (-4525 3800);
FORCEPROP 1 LAST VOLTAGE 0
J 0
(-3950 3725);
PAINT SKYBLUE (-3950 3725);
DISPLAY INVISIBLE (-3950 3725);
FORCEPROP 1 LAST SIZE 1B
J 0
(-3875 3675);
DISPLAY 1.170213 (-3875 3675);
PAINT AQUA (-3875 3675);
DISPLAY INVISIBLE (-3875 3675);
FORCEPROP 2 LAST CDS_LIB mstr_symbols
J 0
(-3950 3725);
PAINT ORANGE (-3950 3725);
DISPLAY INVISIBLE (-3950 3725);
FORCEPROP 1 LAST PATH I38
J 0
(-3875 3725);
DISPLAY 0.872340 (-3875 3725);
PAINT AQUA (-3875 3725);
DISPLAY INVISIBLE (-3875 3725);
FORCEPROP 1 LAST BODY_TYPE PLUMBING
J 0
(-3995 3682);
DISPLAY 0.340426 (-3995 3682);
PAINT GREEN (-3995 3682);
DISPLAY INVISIBLE (-3995 3682);
FORCEPROP 1 LAST HDL_POWER GND
J 0
(-3950 3875);
DISPLAY 1.170213 (-3950 3875);
PAINT GREEN (-3950 3875);
DISPLAY INVISIBLE (-3950 3875);
FORCEADD CAP_A..1
(-3950 3925);
FORCEPROP 1 LASTPIN (-3950 4025) $PN 1
J 0
(-3940 4005);
DISPLAY 0.617021 (-3940 4005);
PAINT ORANGE (-3940 4005);
FORCEPROP 1 LAST MATERIAL X7R
J 0
(-3900 3825);
DISPLAY 0.617021 (-3900 3825);
PAINT SKYBLUE (-3900 3825);
FORCEPROP 1 LAST VOLTAGE 16V
J 0
(-3900 3925);
DISPLAY 0.617021 (-3900 3925);
PAINT SKYBLUE (-3900 3925);
FORCEPROP 1 LAST PACK_TYPE 0402V
J 0
(-3900 3725);
DISPLAY 0.617021 (-3900 3725);
PAINT SKYBLUE (-3900 3725);
FORCEPROP 1 LAST TOLERANCE 10%
J 0
(-3900 3875);
DISPLAY 0.617021 (-3900 3875);
PAINT SKYBLUE (-3900 3875);
FORCEPROP 1 LAST LOCATION C4D19
J 0
(-3900 4025);
DISPLAY 0.617021 (-3900 4025);
PAINT AQUA (-3900 4025);
FORCEPROP 1 LAST VALUE 0.1UF
J 0
(-3900 3975);
DISPLAY 0.617021 (-3900 3975);
PAINT SKYBLUE (-3900 3975);
FORCEPROP 1 LASTPIN (-3950 3825) $PN 2
J 0
(-3940 3805);
DISPLAY 0.617021 (-3940 3805);
PAINT ORANGE (-3940 3805);
FORCEPROP 1 LAST PART_NUMBER A36096-030
J 0
(-3900 3775);
DISPLAY 0.617021 (-3900 3775);
PAINT BLUE (-3900 3775);
FORCEPROP 2 LAST CDS_LOCATION C4D19
J 0
(-3900 4025);
DISPLAY 0.617021 (-3900 4025);
PAINT AQUA (-3900 4025);
DISPLAY INVISIBLE (-3900 4025);
FORCEPROP 2 LAST CDS_LIB dev_discrete
J 0
(-3950 3925);
PAINT ORANGE (-3950 3925);
DISPLAY INVISIBLE (-3950 3925);
FORCEPROP 2 LAST CDS_SEC 1
J 0
(-3900 4075);
PAINT ORANGE (-3900 4075);
DISPLAY INVISIBLE (-3900 4075);
FORCEPROP 2 LAST ROOM PVCCIN_CPU0_VR
J 0
(-3900 4075);
DISPLAY 1.361702 (-3900 4075);
PAINT ORANGE (-3900 4075);
DISPLAY INVISIBLE (-3900 4075);
FORCEPROP 1 LAST PATH I39
J 0
(-3900 4075);
DISPLAY 0.978723 (-3900 4075);
PAINT WHITE (-3900 4075);
DISPLAY INVISIBLE (-3900 4075);
FORCEPROP 2 LAST SEC 1
J 0
(-3900 4125);
DISPLAY 0.680851 (-3900 4125);
PAINT MONO (-3900 4125);
DISPLAY INVISIBLE (-3900 4125);
FORCEPROP 2 LAST SEC_TYPE 0402V
J 0
(-3900 4125);
DISPLAY 1.021277 (-3900 4125);
PAINT ORANGE (-3900 4125);
DISPLAY INVISIBLE (-3900 4125);
FORCEADD OFFPAGE..2
(-1050 2775);
FORCEPROP 2 LAST $XR0 201 
J 0
(-861 2775);
DISPLAY 0.638298 (-861 2775);
PAINT MONO (-861 2775);
FORCEPROP 2 LAST ROOM PVCCIN_CPU0_VR
J 0
(-1475 2850);
DISPLAY 1.361702 (-1475 2850);
PAINT ORANGE (-1475 2850);
DISPLAY INVISIBLE (-1475 2850);
FORCEPROP 2 LAST CDS_LIB mstr_standard
J 0
(-1050 2775);
PAINT ORANGE (-1050 2775);
DISPLAY INVISIBLE (-1050 2775);
FORCEPROP 2 LAST PATH I4
J 0
(-875 2850);
DISPLAY 1.021277 (-875 2850);
PAINT ORANGE (-875 2850);
DISPLAY INVISIBLE (-875 2850);
FORCEPROP 1 LAST OFFPAGE TRUE
J 0
(-725 2650);
DISPLAY 1.170213 (-725 2650);
PAINT GREEN (-725 2650);
DISPLAY INVISIBLE (-725 2650);
FORCEPROP 1 LAST COMMENT_BODY TRUE
J 0
(-1095 2680);
DISPLAY 1.170213 (-1095 2680);
PAINT GREEN (-1095 2680);
DISPLAY INVISIBLE (-1095 2680);
FORCEADD RES..2
(-4250 4275);
FORCEPROP 1 LAST WATTAGE 1/16W
J 0
(-4210 4250);
DISPLAY 0.617021 (-4210 4250);
PAINT SKYBLUE (-4210 4250);
FORCEPROP 1 LASTPIN (-4250 4175) $PN 2
J 0
(-4245 4185);
DISPLAY 0.617021 (-4245 4185);
PAINT ORANGE (-4245 4185);
FORCEPROP 1 LAST TOLERANCE 5%
J 0
(-4205 4300);
DISPLAY 0.617021 (-4205 4300);
PAINT SKYBLUE (-4205 4300);
FORCEPROP 1 LAST VALUE 0.0
J 0
(-4205 4350);
DISPLAY 0.617021 (-4205 4350);
PAINT SKYBLUE (-4205 4350);
FORCEPROP 1 LAST MATERIAL CHIP
J 0
(-4210 4200);
DISPLAY 0.617021 (-4210 4200);
PAINT SKYBLUE (-4210 4200);
FORCEPROP 1 LAST PACK_TYPE 0402
J 0
(-4210 4100);
DISPLAY 0.617021 (-4210 4100);
PAINT SKYBLUE (-4210 4100);
FORCEPROP 1 LAST PART_NUMBER G21497-005
J 0
(-4210 4150);
DISPLAY 0.617021 (-4210 4150);
PAINT BLUE (-4210 4150);
FORCEPROP 1 LAST LOCATION R4D26
J 0
(-4205 4400);
DISPLAY 0.617021 (-4205 4400);
PAINT AQUA (-4205 4400);
FORCEPROP 1 LASTPIN (-4250 4375) $PN 1
J 0
(-4245 4337);
DISPLAY 0.617021 (-4245 4337);
PAINT ORANGE (-4245 4337);
FORCEPROP 2 LAST CDS_LIB mstr_discrete
J 0
(-4250 4275);
PAINT ORANGE (-4250 4275);
DISPLAY INVISIBLE (-4250 4275);
FORCEPROP 2 LAST SEC_TYPE 0402
J 0
(-4200 4500);
DISPLAY 1.021277 (-4200 4500);
PAINT ORANGE (-4200 4500);
DISPLAY INVISIBLE (-4200 4500);
FORCEPROP 2 LAST SEC 1
J 0
(-4200 4500);
DISPLAY 0.680851 (-4200 4500);
PAINT MONO (-4200 4500);
DISPLAY INVISIBLE (-4200 4500);
FORCEPROP 2 LAST CDS_LOCATION R4D26
J 0
(-4205 4400);
DISPLAY 0.617021 (-4205 4400);
PAINT AQUA (-4205 4400);
DISPLAY INVISIBLE (-4205 4400);
FORCEPROP 1 LAST PATH I40
J 0
(-4200 4450);
DISPLAY 0.978723 (-4200 4450);
PAINT WHITE (-4200 4450);
DISPLAY INVISIBLE (-4200 4450);
FORCEPROP 2 LAST ROOM PVCCIN_CPU0_VR
J 0
(-4200 4450);
DISPLAY 1.361702 (-4200 4450);
PAINT ORANGE (-4200 4450);
DISPLAY INVISIBLE (-4200 4450);
FORCEADD GND..1
(-4400 575);
FORCEPROP 3 LASTPIN (-4400 625) SIG_NAME GND\g
J 0
(-4390 635);
DISPLAY 0.659574 (-4390 635);
PAINT MONO (-4390 635);
DISPLAY INVISIBLE (-4390 635);
FORCEPROP 2 LAST ROOM PVCCIN_CPU0_VR
J 0
(-4975 650);
DISPLAY 1.361702 (-4975 650);
PAINT ORANGE (-4975 650);
DISPLAY INVISIBLE (-4975 650);
FORCEPROP 2 LAST CDS_LIB mstr_symbols
J 0
(-4400 575);
PAINT ORANGE (-4400 575);
DISPLAY INVISIBLE (-4400 575);
FORCEPROP 1 LAST VOLTAGE 0
J 0
(-4400 575);
PAINT SKYBLUE (-4400 575);
DISPLAY INVISIBLE (-4400 575);
FORCEPROP 1 LAST PATH I48
J 0
(-4325 575);
DISPLAY 0.872340 (-4325 575);
PAINT AQUA (-4325 575);
DISPLAY INVISIBLE (-4325 575);
FORCEPROP 1 LAST SIZE 1B
J 0
(-4325 525);
DISPLAY 1.170213 (-4325 525);
PAINT AQUA (-4325 525);
DISPLAY INVISIBLE (-4325 525);
FORCEPROP 1 LAST BODY_TYPE PLUMBING
J 0
(-4445 532);
DISPLAY 0.340426 (-4445 532);
PAINT GREEN (-4445 532);
DISPLAY INVISIBLE (-4445 532);
FORCEPROP 1 LAST HDL_POWER GND
J 0
(-4400 725);
DISPLAY 1.170213 (-4400 725);
PAINT GREEN (-4400 725);
DISPLAY INVISIBLE (-4400 725);
FORCEADD OFFPAGE..3
(-1075 2725);
FORCEPROP 2 LAST $XR2 211 
J 0
(-651 2725);
DISPLAY 0.638298 (-651 2725);
PAINT MONO (-651 2725);
FORCEPROP 2 LAST $XR1 194 
J 0
(-771 2725);
DISPLAY 0.638298 (-771 2725);
PAINT MONO (-771 2725);
FORCEPROP 2 LAST $XR0 21 
J 0
(-861 2725);
DISPLAY 0.638298 (-861 2725);
PAINT MONO (-861 2725);
FORCEPROP 2 LAST ROOM PVCCIN_CPU0_VR
J 0
(-1475 2800);
DISPLAY 1.361702 (-1475 2800);
PAINT ORANGE (-1475 2800);
DISPLAY INVISIBLE (-1475 2800);
FORCEPROP 2 LAST CDS_LIB mstr_standard
J 0
(-1075 2725);
PAINT ORANGE (-1075 2725);
DISPLAY INVISIBLE (-1075 2725);
FORCEPROP 2 LAST PATH I5
J 0
(-875 2800);
DISPLAY 1.021277 (-875 2800);
PAINT ORANGE (-875 2800);
DISPLAY INVISIBLE (-875 2800);
FORCEPROP 1 LAST OFFPAGE TRUE
J 0
(-750 2600);
DISPLAY 1.170213 (-750 2600);
PAINT GREEN (-750 2600);
DISPLAY INVISIBLE (-750 2600);
FORCEPROP 1 LAST COMMENT_BODY TRUE
J 0
(-1125 2625);
DISPLAY 1.170213 (-1125 2625);
PAINT GREEN (-1125 2625);
DISPLAY INVISIBLE (-1125 2625);
FORCEADD GND..1
(-4725 575);
FORCEPROP 3 LASTPIN (-4725 625) SIG_NAME GND\g
J 0
(-4715 635);
DISPLAY 0.659574 (-4715 635);
PAINT MONO (-4715 635);
DISPLAY INVISIBLE (-4715 635);
FORCEPROP 2 LAST ROOM PVCCIN_CPU0_VR
J 0
(-5300 650);
DISPLAY 1.361702 (-5300 650);
PAINT ORANGE (-5300 650);
DISPLAY INVISIBLE (-5300 650);
FORCEPROP 1 LAST PATH I50
J 0
(-4650 575);
DISPLAY 0.872340 (-4650 575);
PAINT AQUA (-4650 575);
DISPLAY INVISIBLE (-4650 575);
FORCEPROP 2 LAST CDS_LIB mstr_symbols
J 0
(-4725 575);
PAINT ORANGE (-4725 575);
DISPLAY INVISIBLE (-4725 575);
FORCEPROP 1 LAST SIZE 1B
J 0
(-4650 525);
DISPLAY 1.170213 (-4650 525);
PAINT AQUA (-4650 525);
DISPLAY INVISIBLE (-4650 525);
FORCEPROP 1 LAST VOLTAGE 0
J 0
(-4725 575);
PAINT SKYBLUE (-4725 575);
DISPLAY INVISIBLE (-4725 575);
FORCEPROP 1 LAST BODY_TYPE PLUMBING
J 0
(-4770 532);
DISPLAY 0.340426 (-4770 532);
PAINT GREEN (-4770 532);
DISPLAY INVISIBLE (-4770 532);
FORCEPROP 1 LAST HDL_POWER GND
J 0
(-4725 725);
DISPLAY 1.170213 (-4725 725);
PAINT GREEN (-4725 725);
DISPLAY INVISIBLE (-4725 725);
FORCEADD PVCCIO_CPU0..1
(-5325 4825);
FORCEPROP 3 LASTPIN (-5325 4775) SIG_NAME PVCCIO_CPU0\g
J 0
(-5315 4785);
DISPLAY 0.659574 (-5315 4785);
PAINT MONO (-5315 4785);
DISPLAY INVISIBLE (-5315 4785);
FORCEPROP 1 LAST PATH I51
J 0
(-5275 4850);
DISPLAY 0.872340 (-5275 4850);
PAINT AQUA (-5275 4850);
DISPLAY INVISIBLE (-5275 4850);
FORCEPROP 2 LAST CDS_LIB mstr_symbols
J 0
(-5325 4825);
PAINT ORANGE (-5325 4825);
DISPLAY INVISIBLE (-5325 4825);
FORCEPROP 1 LAST VOLTAGE 1.1V
J 0
(-5370 4782);
DISPLAY 0.340426 (-5370 4782);
PAINT SKYBLUE (-5370 4782);
DISPLAY INVISIBLE (-5370 4782);
FORCEPROP 1 LAST BODY_TYPE PLUMBING
J 0
(-5370 4782);
DISPLAY 0.340426 (-5370 4782);
PAINT GREEN (-5370 4782);
DISPLAY INVISIBLE (-5370 4782);
FORCEPROP 1 LAST HDL_POWER PVCCIO_CPU0
J 1
(-5325 4875);
DISPLAY 0.872340 (-5325 4875);
PAINT GREEN (-5325 4875);
DISPLAY INVISIBLE (-5325 4875);
FORCEADD VCC_CORE..1
(-6050 4825);
FORCEPROP 3 LASTPIN (-6050 4775) SIG_NAME VR_FET_SW_P12V_STBY_PVCCIN_CPU0\g
J 0
(-6040 4785);
DISPLAY 0.659574 (-6040 4785);
PAINT MONO (-6040 4785);
DISPLAY INVISIBLE (-6040 4785);
FORCEPROP 1 LAST HDL_POWER VR_FET_SW_P12V_STBY_PVCCIN_CPU0
J 1
(-6075 4875);
DISPLAY 0.617021 (-6075 4875);
PAINT GREEN (-6075 4875);
FORCEPROP 1 LAST PATH I53
J 0
(-6000 4850);
DISPLAY 0.872340 (-6000 4850);
PAINT AQUA (-6000 4850);
DISPLAY INVISIBLE (-6000 4850);
FORCEPROP 2 LAST CDS_LIB mstr_symbols
J 0
(-6050 4825);
PAINT ORANGE (-6050 4825);
DISPLAY INVISIBLE (-6050 4825);
FORCEADD RES..2
(-6050 4625);
FORCEPROP 1 LASTPIN (-6050 4525) $PN 2
J 0
(-6045 4535);
DISPLAY 0.617021 (-6045 4535);
PAINT ORANGE (-6045 4535);
FORCEPROP 1 LAST PACK_TYPE 0402
J 0
(-6010 4450);
DISPLAY 0.617021 (-6010 4450);
PAINT SKYBLUE (-6010 4450);
FORCEPROP 1 LAST PART_NUMBER G21796-160
J 0
(-6010 4500);
DISPLAY 0.617021 (-6010 4500);
PAINT BLUE (-6010 4500);
FORCEPROP 1 LAST MATERIAL CHIP
J 0
(-6010 4550);
DISPLAY 0.617021 (-6010 4550);
PAINT SKYBLUE (-6010 4550);
FORCEPROP 1 LAST WATTAGE 1/16W
J 0
(-6010 4600);
DISPLAY 0.617021 (-6010 4600);
PAINT SKYBLUE (-6010 4600);
FORCEPROP 1 LAST TOLERANCE 1%
J 0
(-6005 4650);
DISPLAY 0.617021 (-6005 4650);
PAINT SKYBLUE (-6005 4650);
FORCEPROP 1 LASTPIN (-6050 4725) $PN 1
J 0
(-6045 4687);
DISPLAY 0.617021 (-6045 4687);
PAINT ORANGE (-6045 4687);
FORCEPROP 1 LAST VALUE 100.0K
J 0
(-6005 4700);
DISPLAY 0.617021 (-6005 4700);
PAINT SKYBLUE (-6005 4700);
FORCEPROP 1 LAST LOCATION R4D27
J 0
(-6005 4750);
DISPLAY 0.617021 (-6005 4750);
PAINT AQUA (-6005 4750);
FORCEPROP 2 LAST CDS_LIB mstr_discrete
J 0
(-6050 4625);
PAINT ORANGE (-6050 4625);
DISPLAY INVISIBLE (-6050 4625);
FORCEPROP 2 LAST CDS_LOCATION R4D27
J 0
(-6005 4750);
DISPLAY 0.617021 (-6005 4750);
PAINT AQUA (-6005 4750);
DISPLAY INVISIBLE (-6005 4750);
FORCEPROP 1 LAST PATH I54
J 0
(-6000 4800);
DISPLAY 0.978723 (-6000 4800);
PAINT WHITE (-6000 4800);
DISPLAY INVISIBLE (-6000 4800);
FORCEPROP 2 LAST ROOM PVCCIN_CPU0_VR
J 0
(-6000 4800);
DISPLAY 1.361702 (-6000 4800);
PAINT ORANGE (-6000 4800);
DISPLAY INVISIBLE (-6000 4800);
FORCEPROP 2 LAST SEC 1
J 0
(-6000 4850);
DISPLAY 0.680851 (-6000 4850);
PAINT MONO (-6000 4850);
DISPLAY INVISIBLE (-6000 4850);
FORCEPROP 2 LAST SEC_TYPE 0402
J 0
(-6000 4850);
DISPLAY 1.021277 (-6000 4850);
PAINT ORANGE (-6000 4850);
DISPLAY INVISIBLE (-6000 4850);
FORCEADD RES..2
(-6050 4200);
FORCEPROP 1 LAST MATERIAL CHIP
J 0
(-6010 4125);
DISPLAY 0.617021 (-6010 4125);
PAINT SKYBLUE (-6010 4125);
FORCEPROP 1 LAST WATTAGE 1/16W
J 0
(-6010 4175);
DISPLAY 0.617021 (-6010 4175);
PAINT SKYBLUE (-6010 4175);
FORCEPROP 1 LAST TOLERANCE 1%
J 0
(-6005 4225);
DISPLAY 0.617021 (-6005 4225);
PAINT SKYBLUE (-6005 4225);
FORCEPROP 1 LAST VALUE 1.5K
J 0
(-6005 4275);
DISPLAY 0.617021 (-6005 4275);
PAINT SKYBLUE (-6005 4275);
FORCEPROP 1 LAST LOCATION R4D32
J 0
(-6005 4325);
DISPLAY 0.617021 (-6005 4325);
PAINT AQUA (-6005 4325);
FORCEPROP 1 LAST PACK_TYPE 0402
J 0
(-6010 4025);
DISPLAY 0.617021 (-6010 4025);
PAINT SKYBLUE (-6010 4025);
FORCEPROP 1 LAST PART_NUMBER G21796-003
J 0
(-6010 4075);
DISPLAY 0.617021 (-6010 4075);
PAINT BLUE (-6010 4075);
FORCEPROP 1 LASTPIN (-6050 4100) $PN 2
J 0
(-6045 4110);
DISPLAY 0.617021 (-6045 4110);
PAINT ORANGE (-6045 4110);
FORCEPROP 1 LASTPIN (-6050 4300) $PN 1
J 0
(-6045 4262);
DISPLAY 0.617021 (-6045 4262);
PAINT ORANGE (-6045 4262);
FORCEPROP 2 LAST CDS_LIB mstr_discrete
J 0
(-6050 4200);
PAINT ORANGE (-6050 4200);
DISPLAY INVISIBLE (-6050 4200);
FORCEPROP 2 LAST CDS_LOCATION R4D32
J 0
(-6005 4325);
DISPLAY 0.617021 (-6005 4325);
PAINT AQUA (-6005 4325);
DISPLAY INVISIBLE (-6005 4325);
FORCEPROP 2 LAST SEC_TYPE 0402
J 0
(-6000 4425);
DISPLAY 1.021277 (-6000 4425);
PAINT ORANGE (-6000 4425);
DISPLAY INVISIBLE (-6000 4425);
FORCEPROP 2 LAST SEC 1
J 0
(-6000 4425);
DISPLAY 0.680851 (-6000 4425);
PAINT MONO (-6000 4425);
DISPLAY INVISIBLE (-6000 4425);
FORCEPROP 1 LAST PATH I55
J 0
(-6000 4375);
DISPLAY 0.978723 (-6000 4375);
PAINT WHITE (-6000 4375);
DISPLAY INVISIBLE (-6000 4375);
FORCEPROP 2 LAST ROOM PVCCIN_CPU0_VR
J 0
(-6000 4375);
DISPLAY 1.361702 (-6000 4375);
PAINT ORANGE (-6000 4375);
DISPLAY INVISIBLE (-6000 4375);
FORCEADD RES..1
(-5400 3950);
FORCEPROP 1 LAST VALUE 150.0
J 2
(-5450 3900);
DISPLAY 0.617021 (-5450 3900);
PAINT SKYBLUE (-5450 3900);
FORCEPROP 1 LAST MATERIAL CHIP
J 0
(-5300 4000);
DISPLAY 0.617021 (-5300 4000);
PAINT SKYBLUE (-5300 4000);
FORCEPROP 1 LAST TOLERANCE 1%
J 0
(-5400 3900);
DISPLAY 0.617021 (-5400 3900);
PAINT SKYBLUE (-5400 3900);
FORCEPROP 1 LASTPIN (-5500 3950) $PN 1
J 0
(-5488 3962);
DISPLAY 0.617021 (-5488 3962);
PAINT ORANGE (-5488 3962);
FORCEPROP 1 LAST PART_NUMBER G21796-009
J 0
(-5450 4050);
DISPLAY 0.617021 (-5450 4050);
PAINT BLUE (-5450 4050);
FORCEPROP 1 LASTPIN (-5300 3950) $PN 2
J 0
(-5338 3962);
DISPLAY 0.617021 (-5338 3962);
PAINT ORANGE (-5338 3962);
FORCEPROP 1 LAST PACK_TYPE 0402
J 0
(-5300 3900);
DISPLAY 0.617021 (-5300 3900);
PAINT SKYBLUE (-5300 3900);
FORCEPROP 1 LAST LOCATION R4E6
J 0
(-5450 4000);
DISPLAY 0.617021 (-5450 4000);
PAINT AQUA (-5450 4000);
FORCEPROP 1 LAST WATTAGE 1/16W
J 2
(-5450 4000);
DISPLAY 0.617021 (-5450 4000);
PAINT SKYBLUE (-5450 4000);
FORCEPROP 2 LAST CDS_LIB mstr_discrete
J 0
(-5400 3950);
PAINT ORANGE (-5400 3950);
DISPLAY INVISIBLE (-5400 3950);
FORCEPROP 2 LAST CDS_LOCATION R4E6
J 0
(-5450 4000);
DISPLAY 0.617021 (-5450 4000);
PAINT AQUA (-5450 4000);
DISPLAY INVISIBLE (-5450 4000);
FORCEPROP 2 LAST SEC_TYPE 0402
J 0
(-5450 4150);
DISPLAY 1.021277 (-5450 4150);
PAINT ORANGE (-5450 4150);
DISPLAY INVISIBLE (-5450 4150);
FORCEPROP 2 LAST SEC 1
J 0
(-5450 4150);
DISPLAY 0.680851 (-5450 4150);
PAINT MONO (-5450 4150);
DISPLAY INVISIBLE (-5450 4150);
FORCEPROP 1 LAST PATH I56
J 0
(-5450 4100);
DISPLAY 0.978723 (-5450 4100);
PAINT WHITE (-5450 4100);
DISPLAY INVISIBLE (-5450 4100);
FORCEPROP 2 LAST ROOM PVCCIN_CPU0_VR
J 0
(-5500 4175);
DISPLAY 1.361702 (-5500 4175);
PAINT ORANGE (-5500 4175);
DISPLAY INVISIBLE (-5500 4175);
FORCEADD GND..1
(-6050 3975);
FORCEPROP 3 LASTPIN (-6050 4025) SIG_NAME GND\g
J 0
(-6040 4035);
DISPLAY 0.659574 (-6040 4035);
PAINT MONO (-6040 4035);
DISPLAY INVISIBLE (-6040 4035);
FORCEPROP 1 LAST PATH I58
J 0
(-5975 3975);
DISPLAY 0.872340 (-5975 3975);
PAINT AQUA (-5975 3975);
DISPLAY INVISIBLE (-5975 3975);
FORCEPROP 2 LAST CDS_LIB mstr_symbols
J 0
(-6050 3975);
PAINT ORANGE (-6050 3975);
DISPLAY INVISIBLE (-6050 3975);
FORCEPROP 1 LAST SIZE 1B
J 0
(-5975 3925);
DISPLAY 1.170213 (-5975 3925);
PAINT AQUA (-5975 3925);
DISPLAY INVISIBLE (-5975 3925);
FORCEPROP 1 LAST VOLTAGE 0
J 0
(-6050 3975);
PAINT SKYBLUE (-6050 3975);
DISPLAY INVISIBLE (-6050 3975);
FORCEPROP 2 LAST ROOM PVCCIN_CPU0_VR
J 0
(-6625 4050);
DISPLAY 1.361702 (-6625 4050);
PAINT ORANGE (-6625 4050);
DISPLAY INVISIBLE (-6625 4050);
FORCEPROP 1 LAST BODY_TYPE PLUMBING
J 0
(-6095 3932);
DISPLAY 0.340426 (-6095 3932);
PAINT GREEN (-6095 3932);
DISPLAY INVISIBLE (-6095 3932);
FORCEPROP 1 LAST HDL_POWER GND
J 0
(-6050 4125);
DISPLAY 1.170213 (-6050 4125);
PAINT GREEN (-6050 4125);
DISPLAY INVISIBLE (-6050 4125);
FORCEADD OFFPAGE..2
(-1050 2675);
FORCEPROP 2 LAST $XR0 190 
J 0
(-861 2675);
DISPLAY 0.638298 (-861 2675);
PAINT MONO (-861 2675);
FORCEPROP 2 LAST ROOM PVCCIN_CPU0_VR
J 0
(-1475 2750);
DISPLAY 1.361702 (-1475 2750);
PAINT ORANGE (-1475 2750);
DISPLAY INVISIBLE (-1475 2750);
FORCEPROP 2 LAST CDS_LIB mstr_standard
J 0
(-1050 2675);
PAINT ORANGE (-1050 2675);
DISPLAY INVISIBLE (-1050 2675);
FORCEPROP 2 LAST PATH I6
J 0
(-875 2750);
DISPLAY 1.021277 (-875 2750);
PAINT ORANGE (-875 2750);
DISPLAY INVISIBLE (-875 2750);
FORCEPROP 1 LAST OFFPAGE TRUE
J 0
(-725 2550);
DISPLAY 1.170213 (-725 2550);
PAINT GREEN (-725 2550);
DISPLAY INVISIBLE (-725 2550);
FORCEPROP 1 LAST COMMENT_BODY TRUE
J 0
(-1095 2580);
DISPLAY 1.170213 (-1095 2580);
PAINT GREEN (-1095 2580);
DISPLAY INVISIBLE (-1095 2580);
FORCEADD GND..1
(-6600 4025);
FORCEPROP 3 LASTPIN (-6600 4075) SIG_NAME GND\g
J 0
(-6590 4085);
DISPLAY 0.659574 (-6590 4085);
PAINT MONO (-6590 4085);
DISPLAY INVISIBLE (-6590 4085);
FORCEPROP 1 LAST PATH I61
J 0
(-6525 4025);
DISPLAY 0.872340 (-6525 4025);
PAINT AQUA (-6525 4025);
DISPLAY INVISIBLE (-6525 4025);
FORCEPROP 2 LAST CDS_LIB mstr_symbols
J 0
(-6600 4025);
PAINT ORANGE (-6600 4025);
DISPLAY INVISIBLE (-6600 4025);
FORCEPROP 1 LAST SIZE 1B
J 0
(-6525 3975);
DISPLAY 1.170213 (-6525 3975);
PAINT AQUA (-6525 3975);
DISPLAY INVISIBLE (-6525 3975);
FORCEPROP 1 LAST VOLTAGE 0
J 0
(-6600 4025);
PAINT SKYBLUE (-6600 4025);
DISPLAY INVISIBLE (-6600 4025);
FORCEPROP 2 LAST ROOM PVCCIN_CPU0_VR
J 0
(-7175 4100);
DISPLAY 1.361702 (-7175 4100);
PAINT ORANGE (-7175 4100);
DISPLAY INVISIBLE (-7175 4100);
FORCEPROP 1 LAST BODY_TYPE PLUMBING
J 0
(-6645 3982);
DISPLAY 0.340426 (-6645 3982);
PAINT GREEN (-6645 3982);
DISPLAY INVISIBLE (-6645 3982);
FORCEPROP 1 LAST HDL_POWER GND
J 0
(-6600 4175);
DISPLAY 1.170213 (-6600 4175);
PAINT GREEN (-6600 4175);
DISPLAY INVISIBLE (-6600 4175);
FORCEADD CAP..1
(-5550 2075);
FORCEPROP 1 LASTPIN (-5550 2175) $PN 1
J 0
(-5540 2155);
DISPLAY 0.617021 (-5540 2155);
PAINT ORANGE (-5540 2155);
FORCEPROP 1 LAST LOCATION C4D29
J 0
(-5800 2125);
DISPLAY 0.617021 (-5800 2125);
PAINT AQUA (-5800 2125);
FORCEPROP 1 LAST TOLERANCE 10%
J 0
(-5725 2025);
DISPLAY 0.617021 (-5725 2025);
PAINT SKYBLUE (-5725 2025);
FORCEPROP 1 LAST PART_NUMBER A36096-050
J 0
(-5925 2075);
DISPLAY 0.617021 (-5925 2075);
PAINT BLUE (-5925 2075);
FORCEPROP 1 LAST VALUE 220PF
J 0
(-5925 2025);
DISPLAY 0.617021 (-5925 2025);
PAINT SKYBLUE (-5925 2025);
FORCEPROP 1 LAST MATERIAL X7R
J 0
(-5900 1950);
DISPLAY 0.617021 (-5900 1950);
PAINT SKYBLUE (-5900 1950);
FORCEPROP 1 LAST VOLTAGE 50V
J 0
(-6050 1950);
DISPLAY 0.617021 (-6050 1950);
PAINT SKYBLUE (-6050 1950);
FORCEPROP 1 LAST PACK_TYPE 0402LF
J 0
(-5775 1950);
DISPLAY 0.617021 (-5775 1950);
PAINT SKYBLUE (-5775 1950);
FORCEPROP 1 LASTPIN (-5550 1975) $PN 2
J 0
(-5540 1955);
DISPLAY 0.617021 (-5540 1955);
PAINT ORANGE (-5540 1955);
FORCEPROP 2 LAST ROOM PVCCIN_CPU0_VR
J 0
(-5800 2175);
DISPLAY 1.361702 (-5800 2175);
PAINT ORANGE (-5800 2175);
DISPLAY INVISIBLE (-5800 2175);
FORCEPROP 2 LAST CDS_LOCATION C4D29
J 0
(-5800 2125);
DISPLAY 0.617021 (-5800 2125);
PAINT AQUA (-5800 2125);
DISPLAY INVISIBLE (-5800 2125);
FORCEPROP 2 LAST CDS_LIB mstr_discrete
J 0
(-5550 2075);
PAINT ORANGE (-5550 2075);
DISPLAY INVISIBLE (-5550 2075);
FORCEPROP 1 LAST PATH I64
J 0
(-5500 2225);
DISPLAY 0.978723 (-5500 2225);
PAINT WHITE (-5500 2225);
DISPLAY INVISIBLE (-5500 2225);
FORCEPROP 2 LAST SEC 1
J 0
(-5500 2275);
DISPLAY 0.680851 (-5500 2275);
PAINT MONO (-5500 2275);
DISPLAY INVISIBLE (-5500 2275);
FORCEPROP 2 LAST SEC_TYPE 0402LF
J 0
(-5500 2275);
DISPLAY 1.021277 (-5500 2275);
PAINT ORANGE (-5500 2275);
DISPLAY INVISIBLE (-5500 2275);
FORCEPROP 2 LAST NO_XNET_CONNECTION 1
J 0
(-5500 2275);
PAINT MONO (-5500 2275);
DISPLAY INVISIBLE (-5500 2275);
FORCEADD CAP..1
(-5425 1275);
FORCEPROP 1 LAST TOLERANCE 10%
J 0
(-5225 1325);
DISPLAY 0.617021 (-5225 1325);
PAINT SKYBLUE (-5225 1325);
FORCEPROP 1 LAST VOLTAGE 50V
J 0
(-5375 1275);
DISPLAY 0.617021 (-5375 1275);
PAINT SKYBLUE (-5375 1275);
FORCEPROP 1 LAST VALUE 220PF
J 0
(-5375 1325);
DISPLAY 0.617021 (-5375 1325);
PAINT SKYBLUE (-5375 1325);
FORCEPROP 1 LAST PACK_TYPE 0402LF
J 0
(-5375 1175);
DISPLAY 0.617021 (-5375 1175);
PAINT SKYBLUE (-5375 1175);
FORCEPROP 1 LAST MATERIAL X7R
J 0
(-5250 1275);
DISPLAY 0.617021 (-5250 1275);
PAINT SKYBLUE (-5250 1275);
FORCEPROP 1 LASTPIN (-5425 1375) $PN 1
J 0
(-5415 1355);
DISPLAY 0.617021 (-5415 1355);
PAINT ORANGE (-5415 1355);
FORCEPROP 1 LASTPIN (-5425 1175) $PN 2
J 0
(-5415 1155);
DISPLAY 0.617021 (-5415 1155);
PAINT ORANGE (-5415 1155);
FORCEPROP 1 LAST LOCATION C4D17
J 0
(-5375 1375);
DISPLAY 0.617021 (-5375 1375);
PAINT AQUA (-5375 1375);
FORCEPROP 1 LAST PART_NUMBER A36096-050
J 0
(-5375 1225);
DISPLAY 0.617021 (-5375 1225);
PAINT BLUE (-5375 1225);
FORCEPROP 2 LAST SEC_TYPE 0402LF
J 0
(-5375 1475);
DISPLAY 1.021277 (-5375 1475);
PAINT ORANGE (-5375 1475);
DISPLAY INVISIBLE (-5375 1475);
FORCEPROP 2 LAST SEC 1
J 0
(-5375 1475);
DISPLAY 0.680851 (-5375 1475);
PAINT MONO (-5375 1475);
DISPLAY INVISIBLE (-5375 1475);
FORCEPROP 2 LAST CDS_LOCATION C4D17
J 0
(-5375 1375);
DISPLAY 0.617021 (-5375 1375);
PAINT AQUA (-5375 1375);
DISPLAY INVISIBLE (-5375 1375);
FORCEPROP 1 LAST PATH I66
J 0
(-5375 1425);
DISPLAY 0.978723 (-5375 1425);
PAINT WHITE (-5375 1425);
DISPLAY INVISIBLE (-5375 1425);
FORCEPROP 2 LAST ROOM PVCCIN_CPU0_VR
J 0
(-5375 1425);
DISPLAY 1.361702 (-5375 1425);
PAINT ORANGE (-5375 1425);
DISPLAY INVISIBLE (-5375 1425);
FORCEPROP 2 LAST CDS_LIB mstr_discrete
J 0
(-5425 1275);
PAINT ORANGE (-5425 1275);
DISPLAY INVISIBLE (-5425 1275);
FORCEADD GND..1
(-5425 1025);
FORCEPROP 3 LASTPIN (-5425 1075) SIG_NAME GND\g
J 0
(-5415 1085);
DISPLAY 0.659574 (-5415 1085);
PAINT MONO (-5415 1085);
DISPLAY INVISIBLE (-5415 1085);
FORCEPROP 1 LAST HDL_POWER GND
J 0
(-5425 1175);
DISPLAY 1.170213 (-5425 1175);
PAINT GREEN (-5425 1175);
DISPLAY INVISIBLE (-5425 1175);
FORCEPROP 1 LAST BODY_TYPE PLUMBING
J 0
(-5470 982);
DISPLAY 0.340426 (-5470 982);
PAINT GREEN (-5470 982);
DISPLAY INVISIBLE (-5470 982);
FORCEPROP 1 LAST PATH I67
J 0
(-5350 1025);
DISPLAY 0.872340 (-5350 1025);
PAINT AQUA (-5350 1025);
DISPLAY INVISIBLE (-5350 1025);
FORCEPROP 2 LAST CDS_LIB mstr_symbols
J 0
(-5425 1025);
PAINT ORANGE (-5425 1025);
DISPLAY INVISIBLE (-5425 1025);
FORCEPROP 1 LAST VOLTAGE 0
J 0
(-5425 1025);
PAINT SKYBLUE (-5425 1025);
DISPLAY INVISIBLE (-5425 1025);
FORCEPROP 2 LAST ROOM PVCCIN_CPU0_VR
J 0
(-6000 1100);
DISPLAY 1.361702 (-6000 1100);
PAINT ORANGE (-6000 1100);
DISPLAY INVISIBLE (-6000 1100);
FORCEPROP 1 LAST SIZE 1B
J 0
(-5350 975);
DISPLAY 1.170213 (-5350 975);
PAINT AQUA (-5350 975);
DISPLAY INVISIBLE (-5350 975);
FORCEADD CAP..1
R 2
(-5125 1000);
FORCEPROP 1 LAST VALUE 220PF
J 2
(-5175 1050);
DISPLAY 0.617021 (-5175 1050);
PAINT SKYBLUE (-5175 1050);
FORCEPROP 1 LAST VOLTAGE 50V
J 2
(-5175 1000);
DISPLAY 0.617021 (-5175 1000);
PAINT SKYBLUE (-5175 1000);
FORCEPROP 1 LAST PACK_TYPE 0402LF
J 2
(-5175 900);
DISPLAY 0.617021 (-5175 900);
PAINT SKYBLUE (-5175 900);
FORCEPROP 1 LAST LOCATION C4D18
J 2
(-5175 1100);
DISPLAY 0.617021 (-5175 1100);
PAINT AQUA (-5175 1100);
FORCEPROP 1 LASTPIN (-5125 1100) $PN 1
J 2
(-5135 1080);
DISPLAY 0.617021 (-5135 1080);
PAINT ORANGE (-5135 1080);
FORCEPROP 1 LASTPIN (-5125 900) $PN 2
J 2
(-5135 880);
DISPLAY 0.617021 (-5135 880);
PAINT ORANGE (-5135 880);
FORCEPROP 1 LAST TOLERANCE 10%
J 2
(-5200 850);
DISPLAY 0.617021 (-5200 850);
PAINT SKYBLUE (-5200 850);
FORCEPROP 1 LAST PART_NUMBER A36096-050
J 2
(-5175 950);
DISPLAY 0.617021 (-5175 950);
PAINT BLUE (-5175 950);
FORCEPROP 1 LAST MATERIAL X7R
J 2
(-5300 1000);
DISPLAY 0.617021 (-5300 1000);
PAINT SKYBLUE (-5300 1000);
FORCEPROP 2 LAST CDS_LIB mstr_discrete
J 2
(-5125 1000);
PAINT ORANGE (-5125 1000);
DISPLAY INVISIBLE (-5125 1000);
FORCEPROP 2 LAST SEC_TYPE 0402LF
J 0
(-5175 1200);
DISPLAY 1.021277 (-5175 1200);
PAINT ORANGE (-5175 1200);
DISPLAY INVISIBLE (-5175 1200);
FORCEPROP 1 LAST PATH I68
J 2
(-5175 1150);
DISPLAY 0.978723 (-5175 1150);
PAINT WHITE (-5175 1150);
DISPLAY INVISIBLE (-5175 1150);
FORCEPROP 2 LAST CDS_LOCATION C4D18
J 2
(-5175 1100);
DISPLAY 0.617021 (-5175 1100);
PAINT AQUA (-5175 1100);
DISPLAY INVISIBLE (-5175 1100);
FORCEPROP 2 LAST SEC 1
J 0
(-5175 1200);
DISPLAY 0.680851 (-5175 1200);
PAINT MONO (-5175 1200);
DISPLAY INVISIBLE (-5175 1200);
FORCEPROP 2 LAST ROOM PVCCIN_CPU0_VR
J 0
(-5175 1150);
DISPLAY 1.361702 (-5175 1150);
PAINT ORANGE (-5175 1150);
DISPLAY INVISIBLE (-5175 1150);
FORCEADD GND..1
(-5125 775);
FORCEPROP 3 LASTPIN (-5125 825) SIG_NAME GND\g
J 0
(-5115 835);
DISPLAY 0.659574 (-5115 835);
PAINT MONO (-5115 835);
DISPLAY INVISIBLE (-5115 835);
FORCEPROP 2 LAST ROOM PVCCIN_CPU0_VR
J 0
(-5700 850);
DISPLAY 1.361702 (-5700 850);
PAINT ORANGE (-5700 850);
DISPLAY INVISIBLE (-5700 850);
FORCEPROP 2 LAST CDS_LIB mstr_symbols
J 0
(-5125 775);
PAINT ORANGE (-5125 775);
DISPLAY INVISIBLE (-5125 775);
FORCEPROP 1 LAST VOLTAGE 0
J 0
(-5125 775);
PAINT SKYBLUE (-5125 775);
DISPLAY INVISIBLE (-5125 775);
FORCEPROP 1 LAST PATH I69
J 0
(-5050 775);
DISPLAY 0.872340 (-5050 775);
PAINT AQUA (-5050 775);
DISPLAY INVISIBLE (-5050 775);
FORCEPROP 1 LAST SIZE 1B
J 0
(-5050 725);
DISPLAY 1.170213 (-5050 725);
PAINT AQUA (-5050 725);
DISPLAY INVISIBLE (-5050 725);
FORCEPROP 1 LAST BODY_TYPE PLUMBING
J 0
(-5170 732);
DISPLAY 0.340426 (-5170 732);
PAINT GREEN (-5170 732);
DISPLAY INVISIBLE (-5170 732);
FORCEPROP 1 LAST HDL_POWER GND
J 0
(-5125 925);
DISPLAY 1.170213 (-5125 925);
PAINT GREEN (-5125 925);
DISPLAY INVISIBLE (-5125 925);
FORCEADD OFFPAGE..2
(-1050 2375);
FORCEPROP 2 LAST $XR0 203 
J 0
(-861 2375);
DISPLAY 0.638298 (-861 2375);
PAINT MONO (-861 2375);
FORCEPROP 2 LAST ROOM PVCCIN_CPU0_VR
J 0
(-1475 2450);
DISPLAY 1.361702 (-1475 2450);
PAINT ORANGE (-1475 2450);
DISPLAY INVISIBLE (-1475 2450);
FORCEPROP 2 LAST CDS_LIB mstr_standard
J 0
(-1050 2375);
PAINT ORANGE (-1050 2375);
DISPLAY INVISIBLE (-1050 2375);
FORCEPROP 2 LAST PATH I7
J 0
(-875 2450);
DISPLAY 1.021277 (-875 2450);
PAINT ORANGE (-875 2450);
DISPLAY INVISIBLE (-875 2450);
FORCEPROP 1 LAST OFFPAGE TRUE
J 0
(-725 2250);
DISPLAY 1.170213 (-725 2250);
PAINT GREEN (-725 2250);
DISPLAY INVISIBLE (-725 2250);
FORCEPROP 1 LAST COMMENT_BODY TRUE
J 0
(-1095 2280);
DISPLAY 1.170213 (-1095 2280);
PAINT GREEN (-1095 2280);
DISPLAY INVISIBLE (-1095 2280);
FORCEADD CAP..1
(-6450 2375);
FORCEPROP 1 LAST PART_NUMBER A36096-050
J 0
(-6400 2325);
DISPLAY 0.617021 (-6400 2325);
PAINT BLUE (-6400 2325);
FORCEPROP 1 LAST MATERIAL X7R
J 0
(-6275 2375);
DISPLAY 0.617021 (-6275 2375);
PAINT SKYBLUE (-6275 2375);
FORCEPROP 1 LAST VALUE 220PF
J 0
(-6400 2425);
DISPLAY 0.617021 (-6400 2425);
PAINT SKYBLUE (-6400 2425);
FORCEPROP 1 LAST LOCATION C4D45
J 0
(-6400 2475);
DISPLAY 0.617021 (-6400 2475);
PAINT AQUA (-6400 2475);
FORCEPROP 2 LAST NO_XNET_CONNECTION 1
J 0
(-6400 2575);
PAINT MONO (-6400 2575);
FORCEPROP 1 LAST VOLTAGE 50V
J 0
(-6400 2375);
DISPLAY 0.617021 (-6400 2375);
PAINT SKYBLUE (-6400 2375);
FORCEPROP 1 LAST PACK_TYPE 0402LF
J 0
(-6400 2275);
DISPLAY 0.617021 (-6400 2275);
PAINT SKYBLUE (-6400 2275);
FORCEPROP 1 LAST TOLERANCE 10%
J 0
(-6225 2425);
DISPLAY 0.617021 (-6225 2425);
PAINT SKYBLUE (-6225 2425);
FORCEPROP 1 LASTPIN (-6450 2275) $PN 2
J 0
(-6440 2255);
DISPLAY 0.617021 (-6440 2255);
PAINT ORANGE (-6440 2255);
FORCEPROP 1 LASTPIN (-6450 2475) $PN 1
J 0
(-6440 2455);
DISPLAY 0.617021 (-6440 2455);
PAINT ORANGE (-6440 2455);
FORCEPROP 2 LAST CDS_LIB mstr_discrete
J 0
(-6450 2375);
PAINT ORANGE (-6450 2375);
DISPLAY INVISIBLE (-6450 2375);
FORCEPROP 2 LAST CDS_LOCATION C4D45
J 0
(-6400 2475);
DISPLAY 0.617021 (-6400 2475);
PAINT AQUA (-6400 2475);
DISPLAY INVISIBLE (-6400 2475);
FORCEPROP 2 LAST ROOM PVCCIN_CPU0_VR
J 0
(-6400 2525);
DISPLAY 1.361702 (-6400 2525);
PAINT ORANGE (-6400 2525);
DISPLAY INVISIBLE (-6400 2525);
FORCEPROP 1 LAST PATH I70
J 0
(-6400 2525);
DISPLAY 0.978723 (-6400 2525);
PAINT WHITE (-6400 2525);
DISPLAY INVISIBLE (-6400 2525);
FORCEPROP 2 LAST SEC 1
J 0
(-6400 2575);
DISPLAY 0.680851 (-6400 2575);
PAINT MONO (-6400 2575);
DISPLAY INVISIBLE (-6400 2575);
FORCEPROP 2 LAST SEC_TYPE 0402LF
J 0
(-6400 2575);
DISPLAY 1.021277 (-6400 2575);
PAINT ORANGE (-6400 2575);
DISPLAY INVISIBLE (-6400 2575);
FORCEADD OFFPAGE..2
R 2
(-7375 4425);
FORCEPROP 2 LAST $XR0 201 
J 0
(-7630 4425);
DISPLAY 0.638298 (-7630 4425);
PAINT MONO (-7630 4425);
FORCEPROP 2 LAST ROOM PVCCIN_CPU0_VR
J 0
(-7925 4500);
DISPLAY 1.361702 (-7925 4500);
PAINT ORANGE (-7925 4500);
DISPLAY INVISIBLE (-7925 4500);
FORCEPROP 2 LAST PATH I73
J 0
(-7325 4500);
DISPLAY 1.021277 (-7325 4500);
PAINT ORANGE (-7325 4500);
DISPLAY INVISIBLE (-7325 4500);
FORCEPROP 2 LAST CDS_LIB mstr_standard
J 2
(-7375 4425);
PAINT ORANGE (-7375 4425);
DISPLAY INVISIBLE (-7375 4425);
FORCEPROP 1 LAST OFFPAGE TRUE
J 2
(-7700 4300);
DISPLAY 1.170213 (-7700 4300);
PAINT GREEN (-7700 4300);
DISPLAY INVISIBLE (-7700 4300);
FORCEPROP 1 LAST COMMENT_BODY TRUE
J 2
(-7330 4330);
DISPLAY 1.170213 (-7330 4330);
PAINT GREEN (-7330 4330);
DISPLAY INVISIBLE (-7330 4330);
FORCEADD OFFPAGE..1
(-7400 3950);
FORCEPROP 2 LAST $XR2 211 
J 0
(-7891 3950);
DISPLAY 0.638298 (-7891 3950);
PAINT MONO (-7891 3950);
FORCEPROP 2 LAST $XR1 194 
J 0
(-7771 3950);
DISPLAY 0.638298 (-7771 3950);
PAINT MONO (-7771 3950);
FORCEPROP 2 LAST $XR0 21 
J 0
(-7651 3950);
DISPLAY 0.638298 (-7651 3950);
PAINT MONO (-7651 3950);
FORCEPROP 1 LAST COMMENT_BODY TRUE
J 0
(-7275 3850);
DISPLAY 1.170213 (-7275 3850);
PAINT GREEN (-7275 3850);
DISPLAY INVISIBLE (-7275 3850);
FORCEPROP 1 LAST OFFPAGE TRUE
J 0
(-7075 3825);
DISPLAY 1.170213 (-7075 3825);
PAINT GREEN (-7075 3825);
DISPLAY INVISIBLE (-7075 3825);
FORCEPROP 2 LAST PATH I74
J 0
(-7350 4025);
DISPLAY 1.021277 (-7350 4025);
PAINT ORANGE (-7350 4025);
DISPLAY INVISIBLE (-7350 4025);
FORCEPROP 2 LAST CDS_LIB mstr_standard
J 0
(-7400 3950);
PAINT ORANGE (-7400 3950);
DISPLAY INVISIBLE (-7400 3950);
FORCEPROP 2 LAST ROOM PVCCIN_CPU0_VR
J 0
(-7950 4025);
DISPLAY 1.361702 (-7950 4025);
PAINT ORANGE (-7950 4025);
DISPLAY INVISIBLE (-7950 4025);
FORCEADD OFFPAGE..1
(-7625 3175);
FORCEPROP 2 LAST $XR0 202 
J 0
(-7877 3175);
DISPLAY 0.638298 (-7877 3175);
PAINT MONO (-7877 3175);
FORCEPROP 2 LAST PATH I75
J 0
(-7575 3250);
DISPLAY 1.021277 (-7575 3250);
PAINT ORANGE (-7575 3250);
DISPLAY INVISIBLE (-7575 3250);
FORCEPROP 2 LAST CDS_LIB mstr_standard
J 0
(-7625 3175);
PAINT ORANGE (-7625 3175);
DISPLAY INVISIBLE (-7625 3175);
FORCEPROP 2 LAST ROOM PVCCIN_CPU0_VR
J 0
(-8175 3250);
DISPLAY 1.361702 (-8175 3250);
PAINT ORANGE (-8175 3250);
DISPLAY INVISIBLE (-8175 3250);
FORCEPROP 1 LAST OFFPAGE TRUE
J 0
(-7300 3050);
DISPLAY 1.170213 (-7300 3050);
PAINT GREEN (-7300 3050);
DISPLAY INVISIBLE (-7300 3050);
FORCEPROP 1 LAST COMMENT_BODY TRUE
J 0
(-7500 3075);
DISPLAY 1.170213 (-7500 3075);
PAINT GREEN (-7500 3075);
DISPLAY INVISIBLE (-7500 3075);
FORCEADD OFFPAGE..1
(-7625 3125);
FORCEPROP 2 LAST $XR0 202 
J 0
(-7877 3125);
DISPLAY 0.638298 (-7877 3125);
PAINT MONO (-7877 3125);
FORCEPROP 2 LAST PATH I76
J 0
(-7575 3200);
DISPLAY 1.021277 (-7575 3200);
PAINT ORANGE (-7575 3200);
DISPLAY INVISIBLE (-7575 3200);
FORCEPROP 2 LAST CDS_LIB mstr_standard
J 0
(-7625 3125);
PAINT ORANGE (-7625 3125);
DISPLAY INVISIBLE (-7625 3125);
FORCEPROP 2 LAST ROOM PVCCIN_CPU0_VR
J 0
(-8175 3200);
DISPLAY 1.361702 (-8175 3200);
PAINT ORANGE (-8175 3200);
DISPLAY INVISIBLE (-8175 3200);
FORCEPROP 1 LAST OFFPAGE TRUE
J 0
(-7300 3000);
DISPLAY 1.170213 (-7300 3000);
PAINT GREEN (-7300 3000);
DISPLAY INVISIBLE (-7300 3000);
FORCEPROP 1 LAST COMMENT_BODY TRUE
J 0
(-7500 3025);
DISPLAY 1.170213 (-7500 3025);
PAINT GREEN (-7500 3025);
DISPLAY INVISIBLE (-7500 3025);
FORCEADD OFFPAGE..1
(-7625 3075);
FORCEPROP 2 LAST $XR0 203 
J 0
(-7877 3075);
DISPLAY 0.638298 (-7877 3075);
PAINT MONO (-7877 3075);
FORCEPROP 2 LAST PATH I77
J 0
(-7575 3150);
DISPLAY 1.021277 (-7575 3150);
PAINT ORANGE (-7575 3150);
DISPLAY INVISIBLE (-7575 3150);
FORCEPROP 2 LAST CDS_LIB mstr_standard
J 0
(-7625 3075);
PAINT ORANGE (-7625 3075);
DISPLAY INVISIBLE (-7625 3075);
FORCEPROP 2 LAST ROOM PVCCIN_CPU0_VR
J 0
(-8175 3150);
DISPLAY 1.361702 (-8175 3150);
PAINT ORANGE (-8175 3150);
DISPLAY INVISIBLE (-8175 3150);
FORCEPROP 1 LAST OFFPAGE TRUE
J 0
(-7300 2950);
DISPLAY 1.170213 (-7300 2950);
PAINT GREEN (-7300 2950);
DISPLAY INVISIBLE (-7300 2950);
FORCEPROP 1 LAST COMMENT_BODY TRUE
J 0
(-7500 2975);
DISPLAY 1.170213 (-7500 2975);
PAINT GREEN (-7500 2975);
DISPLAY INVISIBLE (-7500 2975);
FORCEADD OFFPAGE..1
(-7625 2875);
FORCEPROP 2 LAST $XR0 202 
J 0
(-7877 2875);
DISPLAY 0.638298 (-7877 2875);
PAINT MONO (-7877 2875);
FORCEPROP 2 LAST PATH I78
J 0
(-7575 2950);
DISPLAY 1.021277 (-7575 2950);
PAINT ORANGE (-7575 2950);
DISPLAY INVISIBLE (-7575 2950);
FORCEPROP 2 LAST CDS_LIB mstr_standard
J 0
(-7625 2875);
PAINT ORANGE (-7625 2875);
DISPLAY INVISIBLE (-7625 2875);
FORCEPROP 2 LAST ROOM PVCCIN_CPU0_VR
J 0
(-8175 2950);
DISPLAY 1.361702 (-8175 2950);
PAINT ORANGE (-8175 2950);
DISPLAY INVISIBLE (-8175 2950);
FORCEPROP 1 LAST OFFPAGE TRUE
J 0
(-7300 2750);
DISPLAY 1.170213 (-7300 2750);
PAINT GREEN (-7300 2750);
DISPLAY INVISIBLE (-7300 2750);
FORCEPROP 1 LAST COMMENT_BODY TRUE
J 0
(-7500 2775);
DISPLAY 1.170213 (-7500 2775);
PAINT GREEN (-7500 2775);
DISPLAY INVISIBLE (-7500 2775);
FORCEADD OFFPAGE..1
(-7625 3025);
FORCEPROP 2 LAST $XR0 203 
J 0
(-7877 3025);
DISPLAY 0.638298 (-7877 3025);
PAINT MONO (-7877 3025);
FORCEPROP 2 LAST PATH I79
J 0
(-7575 3100);
DISPLAY 1.021277 (-7575 3100);
PAINT ORANGE (-7575 3100);
DISPLAY INVISIBLE (-7575 3100);
FORCEPROP 2 LAST ROOM PVCCIN_CPU0_VR
J 0
(-8175 3100);
DISPLAY 1.361702 (-8175 3100);
PAINT ORANGE (-8175 3100);
DISPLAY INVISIBLE (-8175 3100);
FORCEPROP 2 LAST CDS_LIB mstr_standard
J 0
(-7625 3025);
PAINT ORANGE (-7625 3025);
DISPLAY INVISIBLE (-7625 3025);
FORCEPROP 1 LAST OFFPAGE TRUE
J 0
(-7300 2900);
DISPLAY 1.170213 (-7300 2900);
PAINT GREEN (-7300 2900);
DISPLAY INVISIBLE (-7300 2900);
FORCEPROP 1 LAST COMMENT_BODY TRUE
J 0
(-7500 2925);
DISPLAY 1.170213 (-7500 2925);
PAINT GREEN (-7500 2925);
DISPLAY INVISIBLE (-7500 2925);
FORCEADD OFFPAGE..2
(-1050 2525);
FORCEPROP 2 LAST $XR0 205 
J 0
(-861 2525);
DISPLAY 0.638298 (-861 2525);
PAINT MONO (-861 2525);
FORCEPROP 2 LAST CDS_LIB mstr_standard
J 0
(-1050 2525);
PAINT ORANGE (-1050 2525);
DISPLAY INVISIBLE (-1050 2525);
FORCEPROP 2 LAST ROOM PVCCIN_CPU0_VR
J 0
(-1475 2600);
DISPLAY 1.361702 (-1475 2600);
PAINT ORANGE (-1475 2600);
DISPLAY INVISIBLE (-1475 2600);
FORCEPROP 2 LAST PATH I8
J 0
(-875 2600);
DISPLAY 1.021277 (-875 2600);
PAINT ORANGE (-875 2600);
DISPLAY INVISIBLE (-875 2600);
FORCEPROP 1 LAST OFFPAGE TRUE
J 0
(-725 2400);
DISPLAY 1.170213 (-725 2400);
PAINT GREEN (-725 2400);
DISPLAY INVISIBLE (-725 2400);
FORCEPROP 1 LAST COMMENT_BODY TRUE
J 0
(-1095 2430);
DISPLAY 1.170213 (-1095 2430);
PAINT GREEN (-1095 2430);
DISPLAY INVISIBLE (-1095 2430);
FORCEADD OFFPAGE..1
(-7625 2975);
FORCEPROP 2 LAST $XR0 204 
J 0
(-7877 2975);
DISPLAY 0.638298 (-7877 2975);
PAINT MONO (-7877 2975);
FORCEPROP 2 LAST ROOM PVCCIN_CPU0_VR
J 0
(-8175 3050);
DISPLAY 1.361702 (-8175 3050);
PAINT ORANGE (-8175 3050);
DISPLAY INVISIBLE (-8175 3050);
FORCEPROP 2 LAST PATH I80
J 0
(-7575 3050);
DISPLAY 1.021277 (-7575 3050);
PAINT ORANGE (-7575 3050);
DISPLAY INVISIBLE (-7575 3050);
FORCEPROP 2 LAST CDS_LIB mstr_standard
J 0
(-7625 2975);
PAINT ORANGE (-7625 2975);
DISPLAY INVISIBLE (-7625 2975);
FORCEPROP 1 LAST OFFPAGE TRUE
J 0
(-7300 2850);
DISPLAY 1.170213 (-7300 2850);
PAINT GREEN (-7300 2850);
DISPLAY INVISIBLE (-7300 2850);
FORCEPROP 1 LAST COMMENT_BODY TRUE
J 0
(-7500 2875);
DISPLAY 1.170213 (-7500 2875);
PAINT GREEN (-7500 2875);
DISPLAY INVISIBLE (-7500 2875);
FORCEADD OFFPAGE..1
(-7625 2825);
FORCEPROP 2 LAST $XR0 202 
J 0
(-7877 2825);
DISPLAY 0.638298 (-7877 2825);
PAINT MONO (-7877 2825);
FORCEPROP 2 LAST PATH I82
J 0
(-7575 2900);
DISPLAY 1.021277 (-7575 2900);
PAINT ORANGE (-7575 2900);
DISPLAY INVISIBLE (-7575 2900);
FORCEPROP 2 LAST CDS_LIB mstr_standard
J 0
(-7625 2825);
PAINT ORANGE (-7625 2825);
DISPLAY INVISIBLE (-7625 2825);
FORCEPROP 2 LAST ROOM PVCCIN_CPU0_VR
J 0
(-8175 2900);
DISPLAY 1.361702 (-8175 2900);
PAINT ORANGE (-8175 2900);
DISPLAY INVISIBLE (-8175 2900);
FORCEPROP 1 LAST OFFPAGE TRUE
J 0
(-7300 2700);
DISPLAY 1.170213 (-7300 2700);
PAINT GREEN (-7300 2700);
DISPLAY INVISIBLE (-7300 2700);
FORCEPROP 1 LAST COMMENT_BODY TRUE
J 0
(-7500 2725);
DISPLAY 1.170213 (-7500 2725);
PAINT GREEN (-7500 2725);
DISPLAY INVISIBLE (-7500 2725);
FORCEADD OFFPAGE..1
(-7625 2775);
FORCEPROP 2 LAST $XR0 203 
J 0
(-7877 2775);
DISPLAY 0.638298 (-7877 2775);
PAINT MONO (-7877 2775);
FORCEPROP 2 LAST PATH I83
J 0
(-7575 2850);
DISPLAY 1.021277 (-7575 2850);
PAINT ORANGE (-7575 2850);
DISPLAY INVISIBLE (-7575 2850);
FORCEPROP 2 LAST CDS_LIB mstr_standard
J 0
(-7625 2775);
PAINT ORANGE (-7625 2775);
DISPLAY INVISIBLE (-7625 2775);
FORCEPROP 2 LAST ROOM PVCCIN_CPU0_VR
J 0
(-8175 2850);
DISPLAY 1.361702 (-8175 2850);
PAINT ORANGE (-8175 2850);
DISPLAY INVISIBLE (-8175 2850);
FORCEPROP 1 LAST OFFPAGE TRUE
J 0
(-7300 2650);
DISPLAY 0.936170 (-7300 2650);
PAINT GREEN (-7300 2650);
DISPLAY INVISIBLE (-7300 2650);
FORCEPROP 1 LAST COMMENT_BODY TRUE
J 0
(-7500 2675);
DISPLAY 1.170213 (-7500 2675);
PAINT GREEN (-7500 2675);
DISPLAY INVISIBLE (-7500 2675);
FORCEADD OFFPAGE..1
(-7625 2725);
FORCEPROP 2 LAST $XR0 203 
J 0
(-7877 2725);
DISPLAY 0.638298 (-7877 2725);
PAINT MONO (-7877 2725);
FORCEPROP 2 LAST PATH I84
J 0
(-7575 2800);
DISPLAY 1.021277 (-7575 2800);
PAINT ORANGE (-7575 2800);
DISPLAY INVISIBLE (-7575 2800);
FORCEPROP 2 LAST CDS_LIB mstr_standard
J 0
(-7625 2725);
PAINT ORANGE (-7625 2725);
DISPLAY INVISIBLE (-7625 2725);
FORCEPROP 2 LAST ROOM PVCCIN_CPU0_VR
J 0
(-8175 2800);
DISPLAY 1.361702 (-8175 2800);
PAINT ORANGE (-8175 2800);
DISPLAY INVISIBLE (-8175 2800);
FORCEPROP 1 LAST OFFPAGE TRUE
J 0
(-7300 2600);
DISPLAY 1.170213 (-7300 2600);
PAINT GREEN (-7300 2600);
DISPLAY INVISIBLE (-7300 2600);
FORCEPROP 1 LAST COMMENT_BODY TRUE
J 0
(-7500 2625);
DISPLAY 1.170213 (-7500 2625);
PAINT GREEN (-7500 2625);
DISPLAY INVISIBLE (-7500 2625);
FORCEADD OFFPAGE..1
(-7625 2675);
FORCEPROP 2 LAST $XR0 204 
J 0
(-7877 2675);
DISPLAY 0.638298 (-7877 2675);
PAINT MONO (-7877 2675);
FORCEPROP 2 LAST PATH I85
J 0
(-7575 2750);
DISPLAY 1.021277 (-7575 2750);
PAINT ORANGE (-7575 2750);
DISPLAY INVISIBLE (-7575 2750);
FORCEPROP 2 LAST CDS_LIB mstr_standard
J 0
(-7625 2675);
PAINT ORANGE (-7625 2675);
DISPLAY INVISIBLE (-7625 2675);
FORCEPROP 2 LAST ROOM PVCCIN_CPU0_VR
J 0
(-8175 2750);
DISPLAY 1.361702 (-8175 2750);
PAINT ORANGE (-8175 2750);
DISPLAY INVISIBLE (-8175 2750);
FORCEPROP 1 LAST OFFPAGE TRUE
J 0
(-7300 2550);
DISPLAY 1.170213 (-7300 2550);
PAINT GREEN (-7300 2550);
DISPLAY INVISIBLE (-7300 2550);
FORCEPROP 1 LAST COMMENT_BODY TRUE
J 0
(-7500 2575);
DISPLAY 1.170213 (-7500 2575);
PAINT GREEN (-7500 2575);
DISPLAY INVISIBLE (-7500 2575);
FORCEADD OFFPAGE..1
(-7375 2525);
FORCEPROP 2 LAST $XR0 204 
J 0
(-7657 2525);
DISPLAY 0.638298 (-7657 2525);
PAINT MONO (-7657 2525);
FORCEPROP 2 LAST ROOM PVCCIN_CPU0_VR
J 0
(-7925 2600);
DISPLAY 1.361702 (-7925 2600);
PAINT ORANGE (-7925 2600);
DISPLAY INVISIBLE (-7925 2600);
FORCEPROP 2 LAST CDS_LIB mstr_standard
J 0
(-7375 2525);
PAINT ORANGE (-7375 2525);
DISPLAY INVISIBLE (-7375 2525);
FORCEPROP 2 LAST PATH I87
J 0
(-7325 2600);
DISPLAY 1.021277 (-7325 2600);
PAINT ORANGE (-7325 2600);
DISPLAY INVISIBLE (-7325 2600);
FORCEPROP 1 LAST OFFPAGE TRUE
J 0
(-7050 2400);
DISPLAY 1.170213 (-7050 2400);
PAINT GREEN (-7050 2400);
DISPLAY INVISIBLE (-7050 2400);
FORCEPROP 1 LAST COMMENT_BODY TRUE
J 0
(-7250 2425);
DISPLAY 1.170213 (-7250 2425);
PAINT GREEN (-7250 2425);
DISPLAY INVISIBLE (-7250 2425);
FORCEADD OFFPAGE..1
(-7400 2250);
FORCEPROP 2 LAST $XR0 204 
J 0
(-7682 2250);
DISPLAY 0.638298 (-7682 2250);
PAINT MONO (-7682 2250);
FORCEPROP 2 LAST ROOM PVCCIN_CPU0_VR
J 0
(-7950 2325);
DISPLAY 1.361702 (-7950 2325);
PAINT ORANGE (-7950 2325);
DISPLAY INVISIBLE (-7950 2325);
FORCEPROP 2 LAST CDS_LIB mstr_standard
J 0
(-7400 2250);
PAINT ORANGE (-7400 2250);
DISPLAY INVISIBLE (-7400 2250);
FORCEPROP 2 LAST PATH I88
J 0
(-7350 2325);
DISPLAY 1.021277 (-7350 2325);
PAINT ORANGE (-7350 2325);
DISPLAY INVISIBLE (-7350 2325);
FORCEPROP 1 LAST OFFPAGE TRUE
J 0
(-7075 2125);
DISPLAY 1.170213 (-7075 2125);
PAINT GREEN (-7075 2125);
DISPLAY INVISIBLE (-7075 2125);
FORCEPROP 1 LAST COMMENT_BODY TRUE
J 0
(-7275 2150);
DISPLAY 1.170213 (-7275 2150);
PAINT GREEN (-7275 2150);
DISPLAY INVISIBLE (-7275 2150);
FORCEADD OFFPAGE..1
(-7400 2075);
FORCEPROP 2 LAST $XR0 205 
J 0
(-7682 2075);
DISPLAY 0.638298 (-7682 2075);
PAINT MONO (-7682 2075);
FORCEPROP 2 LAST ROOM PVCCIN_CPU0_VR
J 0
(-7950 2150);
DISPLAY 1.361702 (-7950 2150);
PAINT ORANGE (-7950 2150);
DISPLAY INVISIBLE (-7950 2150);
FORCEPROP 2 LAST CDS_LIB mstr_standard
J 0
(-7400 2075);
PAINT ORANGE (-7400 2075);
DISPLAY INVISIBLE (-7400 2075);
FORCEPROP 2 LAST PATH I89
J 0
(-7350 2150);
DISPLAY 1.021277 (-7350 2150);
PAINT ORANGE (-7350 2150);
DISPLAY INVISIBLE (-7350 2150);
FORCEPROP 1 LAST OFFPAGE TRUE
J 0
(-7075 1950);
DISPLAY 1.170213 (-7075 1950);
PAINT GREEN (-7075 1950);
DISPLAY INVISIBLE (-7075 1950);
FORCEPROP 1 LAST COMMENT_BODY TRUE
J 0
(-7275 1975);
DISPLAY 1.170213 (-7275 1975);
PAINT GREEN (-7275 1975);
DISPLAY INVISIBLE (-7275 1975);
FORCEADD OFFPAGE..2
(-1050 2475);
FORCEPROP 2 LAST $XR0 202 
J 0
(-861 2475);
DISPLAY 0.638298 (-861 2475);
PAINT MONO (-861 2475);
FORCEPROP 2 LAST CDS_LIB mstr_standard
J 0
(-1050 2475);
PAINT ORANGE (-1050 2475);
DISPLAY INVISIBLE (-1050 2475);
FORCEPROP 2 LAST ROOM PVCCIN_CPU0_VR
J 0
(-1475 2550);
DISPLAY 1.361702 (-1475 2550);
PAINT ORANGE (-1475 2550);
DISPLAY INVISIBLE (-1475 2550);
FORCEPROP 2 LAST PATH I9
J 0
(-875 2550);
DISPLAY 1.021277 (-875 2550);
PAINT ORANGE (-875 2550);
DISPLAY INVISIBLE (-875 2550);
FORCEPROP 1 LAST OFFPAGE TRUE
J 0
(-725 2350);
DISPLAY 1.170213 (-725 2350);
PAINT GREEN (-725 2350);
DISPLAY INVISIBLE (-725 2350);
FORCEPROP 1 LAST COMMENT_BODY TRUE
J 0
(-1095 2380);
DISPLAY 1.170213 (-1095 2380);
PAINT GREEN (-1095 2380);
DISPLAY INVISIBLE (-1095 2380);
FORCEADD OFFPAGE..1
(-7400 1925);
FORCEPROP 2 LAST $XR0 205 
J 0
(-7682 1925);
DISPLAY 0.638298 (-7682 1925);
PAINT MONO (-7682 1925);
FORCEPROP 2 LAST PATH I90
J 0
(-7350 2000);
DISPLAY 1.021277 (-7350 2000);
PAINT ORANGE (-7350 2000);
DISPLAY INVISIBLE (-7350 2000);
FORCEPROP 2 LAST CDS_LIB mstr_standard
J 0
(-7400 1925);
PAINT ORANGE (-7400 1925);
DISPLAY INVISIBLE (-7400 1925);
FORCEPROP 2 LAST ROOM PVCCIN_CPU0_VR
J 0
(-7950 2000);
DISPLAY 1.361702 (-7950 2000);
PAINT ORANGE (-7950 2000);
DISPLAY INVISIBLE (-7950 2000);
FORCEPROP 1 LAST OFFPAGE TRUE
J 0
(-7075 1800);
DISPLAY 1.170213 (-7075 1800);
PAINT GREEN (-7075 1800);
DISPLAY INVISIBLE (-7075 1800);
FORCEPROP 1 LAST COMMENT_BODY TRUE
J 0
(-7275 1825);
DISPLAY 1.170213 (-7275 1825);
PAINT GREEN (-7275 1825);
DISPLAY INVISIBLE (-7275 1825);
FORCEADD OFFPAGE..1
(-7400 1875);
FORCEPROP 2 LAST $XR2 204 
J 0
(-7922 1875);
DISPLAY 0.638298 (-7922 1875);
PAINT MONO (-7922 1875);
FORCEPROP 2 LAST $XR1 203 
J 0
(-7802 1875);
DISPLAY 0.638298 (-7802 1875);
PAINT MONO (-7802 1875);
FORCEPROP 2 LAST $XR0 202 
J 0
(-7682 1875);
DISPLAY 0.638298 (-7682 1875);
PAINT MONO (-7682 1875);
FORCEPROP 2 LAST ROOM PVCCIN_CPU0_VR
J 0
(-7950 1950);
DISPLAY 1.361702 (-7950 1950);
PAINT ORANGE (-7950 1950);
DISPLAY INVISIBLE (-7950 1950);
FORCEPROP 2 LAST CDS_LIB mstr_standard
J 0
(-7400 1875);
PAINT ORANGE (-7400 1875);
DISPLAY INVISIBLE (-7400 1875);
FORCEPROP 2 LAST PATH I91
J 0
(-7350 1950);
DISPLAY 1.021277 (-7350 1950);
PAINT ORANGE (-7350 1950);
DISPLAY INVISIBLE (-7350 1950);
FORCEPROP 1 LAST OFFPAGE TRUE
J 0
(-7075 1750);
DISPLAY 1.170213 (-7075 1750);
PAINT GREEN (-7075 1750);
DISPLAY INVISIBLE (-7075 1750);
FORCEPROP 1 LAST COMMENT_BODY TRUE
J 0
(-7275 1775);
DISPLAY 1.170213 (-7275 1775);
PAINT GREEN (-7275 1775);
DISPLAY INVISIBLE (-7275 1775);
FORCEADD OFFPAGE..1
(-7400 1825);
FORCEPROP 2 LAST $XR0 191 
J 0
(-7682 1825);
DISPLAY 0.638298 (-7682 1825);
PAINT MONO (-7682 1825);
FORCEPROP 2 LAST ROOM PVCCIN_CPU0_VR
J 0
(-7950 1900);
DISPLAY 1.361702 (-7950 1900);
PAINT ORANGE (-7950 1900);
DISPLAY INVISIBLE (-7950 1900);
FORCEPROP 2 LAST CDS_LIB mstr_standard
J 0
(-7400 1825);
PAINT ORANGE (-7400 1825);
DISPLAY INVISIBLE (-7400 1825);
FORCEPROP 2 LAST PATH I92
J 0
(-7350 1900);
DISPLAY 1.021277 (-7350 1900);
PAINT ORANGE (-7350 1900);
DISPLAY INVISIBLE (-7350 1900);
FORCEPROP 1 LAST OFFPAGE TRUE
J 0
(-7075 1700);
DISPLAY 1.170213 (-7075 1700);
PAINT GREEN (-7075 1700);
DISPLAY INVISIBLE (-7075 1700);
FORCEPROP 1 LAST COMMENT_BODY TRUE
J 0
(-7275 1725);
DISPLAY 1.170213 (-7275 1725);
PAINT GREEN (-7275 1725);
DISPLAY INVISIBLE (-7275 1725);
FORCEADD OFFPAGE..1
(-7400 1575);
FORCEPROP 2 LAST $XR0 205 
J 0
(-7682 1575);
DISPLAY 0.638298 (-7682 1575);
PAINT MONO (-7682 1575);
FORCEPROP 2 LAST ROOM PVCCIN_CPU0_VR
J 0
(-7950 1650);
DISPLAY 1.361702 (-7950 1650);
PAINT ORANGE (-7950 1650);
DISPLAY INVISIBLE (-7950 1650);
FORCEPROP 2 LAST CDS_LIB mstr_standard
J 0
(-7400 1575);
PAINT ORANGE (-7400 1575);
DISPLAY INVISIBLE (-7400 1575);
FORCEPROP 2 LAST PATH I93
J 0
(-7350 1650);
DISPLAY 1.021277 (-7350 1650);
PAINT ORANGE (-7350 1650);
DISPLAY INVISIBLE (-7350 1650);
FORCEPROP 1 LAST OFFPAGE TRUE
J 0
(-7075 1450);
DISPLAY 1.170213 (-7075 1450);
PAINT GREEN (-7075 1450);
DISPLAY INVISIBLE (-7075 1450);
FORCEPROP 1 LAST COMMENT_BODY TRUE
J 0
(-7275 1475);
DISPLAY 1.170213 (-7275 1475);
PAINT GREEN (-7275 1475);
DISPLAY INVISIBLE (-7275 1475);
FORCEADD OFFPAGE..1
(-7400 1725);
FORCEPROP 2 LAST $XR0 201 
J 0
(-7682 1725);
DISPLAY 0.638298 (-7682 1725);
PAINT MONO (-7682 1725);
FORCEPROP 2 LAST CDS_LIB mstr_standard
J 0
(-7400 1725);
PAINT ORANGE (-7400 1725);
DISPLAY INVISIBLE (-7400 1725);
FORCEPROP 2 LAST PATH I94
J 0
(-7350 1800);
DISPLAY 1.021277 (-7350 1800);
PAINT ORANGE (-7350 1800);
DISPLAY INVISIBLE (-7350 1800);
FORCEPROP 1 LAST COMMENT_BODY TRUE
J 0
(-7275 1625);
DISPLAY 1.170213 (-7275 1625);
PAINT GREEN (-7275 1625);
DISPLAY INVISIBLE (-7275 1625);
FORCEPROP 1 LAST OFFPAGE TRUE
J 0
(-7075 1600);
DISPLAY 1.170213 (-7075 1600);
PAINT GREEN (-7075 1600);
DISPLAY INVISIBLE (-7075 1600);
FORCEPROP 2 LAST ROOM PVCCIN_CPU0_VR
J 0
(-7950 1800);
DISPLAY 1.361702 (-7950 1800);
PAINT ORANGE (-7950 1800);
DISPLAY INVISIBLE (-7950 1800);
FORCEADD OFFPAGE..1
(-7400 1525);
FORCEPROP 2 LAST $XR0 205 
J 0
(-7682 1525);
DISPLAY 0.638298 (-7682 1525);
PAINT MONO (-7682 1525);
FORCEPROP 2 LAST ROOM PVCCIN_CPU0_VR
J 0
(-7950 1600);
DISPLAY 1.361702 (-7950 1600);
PAINT ORANGE (-7950 1600);
DISPLAY INVISIBLE (-7950 1600);
FORCEPROP 2 LAST CDS_LIB mstr_standard
J 0
(-7400 1525);
PAINT ORANGE (-7400 1525);
DISPLAY INVISIBLE (-7400 1525);
FORCEPROP 2 LAST PATH I96
J 0
(-7350 1600);
DISPLAY 1.021277 (-7350 1600);
PAINT ORANGE (-7350 1600);
DISPLAY INVISIBLE (-7350 1600);
FORCEPROP 1 LAST OFFPAGE TRUE
J 0
(-7075 1400);
DISPLAY 1.170213 (-7075 1400);
PAINT GREEN (-7075 1400);
DISPLAY INVISIBLE (-7075 1400);
FORCEPROP 1 LAST COMMENT_BODY TRUE
J 0
(-7275 1425);
DISPLAY 1.170213 (-7275 1425);
PAINT GREEN (-7275 1425);
DISPLAY INVISIBLE (-7275 1425);
FORCEADD OFFPAGE..1
(-7400 1475);
FORCEPROP 2 LAST $XR0 205 
J 0
(-7682 1475);
DISPLAY 0.638298 (-7682 1475);
PAINT MONO (-7682 1475);
FORCEPROP 2 LAST ROOM PVCCIN_CPU0_VR
J 0
(-7950 1550);
DISPLAY 1.361702 (-7950 1550);
PAINT ORANGE (-7950 1550);
DISPLAY INVISIBLE (-7950 1550);
FORCEPROP 2 LAST CDS_LIB mstr_standard
J 0
(-7400 1475);
PAINT ORANGE (-7400 1475);
DISPLAY INVISIBLE (-7400 1475);
FORCEPROP 2 LAST PATH I97
J 0
(-7350 1550);
DISPLAY 1.021277 (-7350 1550);
PAINT ORANGE (-7350 1550);
DISPLAY INVISIBLE (-7350 1550);
FORCEPROP 1 LAST OFFPAGE TRUE
J 0
(-7075 1350);
DISPLAY 1.170213 (-7075 1350);
PAINT GREEN (-7075 1350);
DISPLAY INVISIBLE (-7075 1350);
FORCEPROP 1 LAST COMMENT_BODY TRUE
J 0
(-7275 1375);
DISPLAY 1.170213 (-7275 1375);
PAINT GREEN (-7275 1375);
DISPLAY INVISIBLE (-7275 1375);
FORCEADD RES..1
(-2400 2725);
FORCEPROP 1 LAST TOLERANCE 5%
J 0
(-2475 2575);
DISPLAY 0.617021 (-2475 2575);
PAINT SKYBLUE (-2475 2575);
FORCEPROP 1 LAST VALUE 0.0
J 2
(-2525 2575);
DISPLAY 0.617021 (-2525 2575);
PAINT SKYBLUE (-2525 2575);
FORCEPROP 1 LASTPIN (-2300 2725) $PN 2
J 0
(-2338 2737);
DISPLAY 0.617021 (-2338 2737);
PAINT ORANGE (-2338 2737);
FORCEPROP 1 LASTPIN (-2500 2725) $PN 1
J 0
(-2488 2737);
DISPLAY 0.617021 (-2488 2737);
PAINT ORANGE (-2488 2737);
FORCEPROP 1 LAST LOCATION R4D66
J 0
(-2650 2725);
DISPLAY 0.617021 (-2650 2725);
PAINT AQUA (-2650 2725);
FORCEPROP 1 LAST PACK_TYPE 0402
J 0
(-2375 2575);
DISPLAY 0.617021 (-2375 2575);
PAINT SKYBLUE (-2375 2575);
FORCEPROP 1 LAST MATERIAL CHIP
J 0
(-2375 2525);
DISPLAY 0.617021 (-2375 2525);
PAINT SKYBLUE (-2375 2525);
FORCEPROP 1 LAST WATTAGE 1/16W
J 2
(-2425 2525);
DISPLAY 0.617021 (-2425 2525);
PAINT SKYBLUE (-2425 2525);
FORCEPROP 1 LAST PART_NUMBER G21497-005
J 0
(-2550 2625);
DISPLAY 0.617021 (-2550 2625);
PAINT BLUE (-2550 2625);
FORCEPROP 2 LAST CDS_LOCATION R4D66
J 0
(-2450 2775);
DISPLAY 0.617021 (-2450 2775);
PAINT AQUA (-2450 2775);
DISPLAY INVISIBLE (-2450 2775);
FORCEPROP 2 LAST CDS_LIB mstr_discrete
J 0
(-2400 2725);
PAINT ORANGE (-2400 2725);
DISPLAY INVISIBLE (-2400 2725);
FORCEPROP 2 LAST SEC_TYPE 0402
J 0
(-2450 2925);
DISPLAY 1.021277 (-2450 2925);
PAINT ORANGE (-2450 2925);
DISPLAY INVISIBLE (-2450 2925);
FORCEPROP 2 LAST SEC 1
J 0
(-2450 2925);
DISPLAY 0.680851 (-2450 2925);
PAINT MONO (-2450 2925);
DISPLAY INVISIBLE (-2450 2925);
FORCEPROP 1 LAST PATH I98
J 0
(-2450 2875);
DISPLAY 0.978723 (-2450 2875);
PAINT WHITE (-2450 2875);
DISPLAY INVISIBLE (-2450 2875);
FORCEPROP 2 LAST ROOM PVCCIN_CPU0_VR
J 0
(-2450 2825);
DISPLAY 1.361702 (-2450 2825);
PAINT ORANGE (-2450 2825);
DISPLAY INVISIBLE (-2450 2825);
FORCEADD DNS..2
(-5645 4270);
PAINT RED (-5645 4270);
FORCEPROP 1 LAST COMMENT_BODY TRUE
R 1
J 0
(-5570 4045);
DISPLAY 0.872340 (-5570 4045);
PAINT GREEN (-5570 4045);
DISPLAY INVISIBLE (-5570 4045);
FORCEPROP 2 LAST CDS_LIB mstr_misc
J 0
(-5645 4270);
PAINT ORANGE (-5645 4270);
DISPLAY INVISIBLE (-5645 4270);
FORCEADD DNS..2
(-2070 3745);
PAINT RED (-2070 3745);
FORCEPROP 2 LAST CDS_LIB mstr_misc
J 0
(-2070 3745);
PAINT ORANGE (-2070 3745);
DISPLAY INVISIBLE (-2070 3745);
FORCEPROP 1 LAST COMMENT_BODY TRUE
R 1
J 0
(-1995 3520);
DISPLAY 0.872340 (-1995 3520);
PAINT GREEN (-1995 3520);
DISPLAY INVISIBLE (-1995 3520);
FORCEADD DESIGN_NOTE..1
(-1200 4900);
PAINT PURPLE (-1200 4900);
FORCEPROP 0 LAST L2 PVCCIN_CPU0: 0X00(BUS #1)
J 0
(-1400 4625);
DISPLAY 1.021277 (-1400 4625);
PAINT VIOLET (-1400 4625);
FORCEPROP 0 LAST L3 PVSA_CPU0: 0X01(BUS #1)
J 0
(-1400 4700);
DISPLAY 1.021277 (-1400 4700);
PAINT VIOLET (-1400 4700);
FORCEPROP 0 LAST L1 SVID ADDRESS
J 0
(-1400 4775);
PAINT VIOLET (-1400 4775);
FORCEPROP 1 LAST COMMENT_BODY TRUE
J 0
(-1175 5000);
DISPLAY 1.319149 (-1175 5000);
PAINT GREEN (-1175 5000);
DISPLAY INVISIBLE (-1175 5000);
FORCEPROP 2 LAST CDS_LIB mstr_symbols
J 0
(-1200 4900);
PAINT MONO (-1200 4900);
DISPLAY INVISIBLE (-1200 4900);
FORCEPROP 2 LAST BOM_COST SM_CONTROLLER
J 0
(-1400 4850);
PAINT MONO (-1400 4850);
DISPLAY INVISIBLE (-1400 4850);
FORCEPROP 2 LAST ROOM PVCCIN_CPU0_VR
J 0
(-1400 4850);
PAINT MONO (-1400 4850);
DISPLAY INVISIBLE (-1400 4850);
FORCEADD DNS..2
(-1095 1995);
PAINT RED (-1095 1995);
FORCEPROP 2 LAST CDS_LIB mstr_misc
J 0
(-1095 1995);
PAINT ORANGE (-1095 1995);
DISPLAY INVISIBLE (-1095 1995);
FORCEPROP 1 LAST COMMENT_BODY TRUE
R 1
J 0
(-1020 1770);
DISPLAY 0.872340 (-1020 1770);
PAINT GREEN (-1020 1770);
DISPLAY INVISIBLE (-1020 1770);
FORCEADD DESIGN_NOTE..1
(-3125 550);
FORCEPROP 0 LAST L1 REMOVE VR DONGLE HEADER IN MASS PRODUCTION
J 0
(-3325 425);
DISPLAY 0.617021 (-3325 425);
PAINT WHITE (-3325 425);
FORCEPROP 2 LAST CDS_LIB mstr_symbols
J 0
(-3125 550);
PAINT WHITE (-3125 550);
DISPLAY INVISIBLE (-3125 550);
FORCEPROP 1 LAST COMMENT_BODY TRUE
J 0
(-3100 650);
DISPLAY 1.319149 (-3100 650);
PAINT WHITE (-3100 650);
DISPLAY INVISIBLE (-3100 650);
FORCEADD DNS..2
(-820 1995);
PAINT RED (-820 1995);
FORCEPROP 2 LAST CDS_LIB mstr_misc
J 0
(-820 1995);
PAINT ORANGE (-820 1995);
DISPLAY INVISIBLE (-820 1995);
FORCEPROP 1 LAST COMMENT_BODY TRUE
R 1
J 0
(-745 1770);
DISPLAY 0.872340 (-745 1770);
PAINT GREEN (-745 1770);
DISPLAY INVISIBLE (-745 1770);
FORCEADD DESIGN_NOTE..1
(-4100 1425);
FORCEPROP 0 LAST L1 SMBUS ADDRESS: 0X90
J 0
(-4300 1300);
DISPLAY 1.021277 (-4300 1300);
PAINT VIOLET (-4300 1300);
FORCEPROP 2 LAST CDS_LIB mstr_symbols
J 0
(-4100 1425);
PAINT ORANGE (-4100 1425);
DISPLAY INVISIBLE (-4100 1425);
FORCEPROP 1 LAST COMMENT_BODY TRUE
J 0
(-4075 1525);
DISPLAY 0.978723 (-4075 1525);
PAINT ORANGE (-4075 1525);
DISPLAY INVISIBLE (-4075 1525);
FORCEADD INTEL_CORP_BPAGE..1
(-125 0);
FORCEPROP 1 LAST CDS_CON_LAST_MODIFIED Fri Jun 16 17:49:13 2017
J 0
(-1550 325);
PAINT ORANGE (-1550 325);
DISPLAY INVISIBLE (-1550 325);
FORCEPROP 1 LAST CUSTOM_TXT_CDS <CURRENT_DESIGN_SHEET> OF <TOTAL_DESIGN_SHEETS>
J 0
(-625 25);
PAINT ORANGE (-625 25);
FORCEPROP 1 LAST CUSTOM_TXT_CDS <CON_LAST_MODIFIED>
J 0
(-4125 100);
PAINT ORANGE (-4125 100);
FORCEPROP 2 LAST CUSTOM_TXT_CDS <XR_PAGE_TITLE>
J 0
(-8015 5250);
DISPLAY 0.638298 (-8015 5250);
PAINT PINK (-8015 5250);
DISPLAY INVISIBLE (-8015 5250);
FORCEPROP 1 LAST SCH_TITLE VCCIN CPU0 (1 OF 4)
J 0
(-8075 50);
DISPLAY 1.212766 (-8075 50);
PAINT ORANGE (-8075 50);
FORCEPROP 2 LAST CDS_LIB mstr_symbols
J 0
(-125 0);
PAINT MONO (-125 0);
DISPLAY INVISIBLE (-125 0);
FORCEPROP 2 LAST PAGE_BORDER TRUE
J 0
(-8015 5250);
DISPLAY 0.638298 (-8015 5250);
PAINT PINK (-8015 5250);
DISPLAY INVISIBLE (-8015 5250);
FORCEPROP 1 LAST COMMENT_BODY TRUE
J 0
(-113 12);
DISPLAY 0.468085 (-113 12);
PAINT GREEN (-113 12);
DISPLAY INVISIBLE (-113 12);
FORCEPROP 2 LAST CDS_XR_PAGE_TITLE CR-201 : @BASEBOARD_FAB2_LIB.BASEBOARD_FAB2(SCH_1):PAGE201
J 0
(-8015 5250);
DISPLAY 0.638298 (-8015 5250);
PAINT PINK (-8015 5250);
DISPLAY INVISIBLE (-8015 5250);
FORCEADD DNS..2
(-1570 4195);
PAINT RED (-1570 4195);
FORCEPROP 2 LAST CDS_LIB mstr_misc
J 0
(-1570 4195);
PAINT ORANGE (-1570 4195);
DISPLAY INVISIBLE (-1570 4195);
FORCEPROP 1 LAST COMMENT_BODY TRUE
R 1
J 0
(-1495 3970);
DISPLAY 0.872340 (-1495 3970);
PAINT GREEN (-1495 3970);
DISPLAY INVISIBLE (-1495 3970);
FORCEADD DNS..2
(-1270 3745);
PAINT RED (-1270 3745);
FORCEPROP 1 LAST COMMENT_BODY TRUE
R 1
J 0
(-1195 3520);
DISPLAY 0.872340 (-1195 3520);
PAINT GREEN (-1195 3520);
DISPLAY INVISIBLE (-1195 3520);
FORCEPROP 2 LAST CDS_LIB mstr_misc
J 0
(-1270 3745);
PAINT ORANGE (-1270 3745);
DISPLAY INVISIBLE (-1270 3745);
WIRE 16 -1 (-4250 4550)(-4250 4375);
WIRE 16 -1 (-3050 4375)(-3050 4500);
WIRE 16 -1 (-3050 4375)(-2775 4375);
WIRE 16 -1 (-3050 4225)(-3050 4375);
WIRE 16 -1 (-2775 4375)(-2500 4375);
WIRE 16 -1 (-2775 4025)(-2775 4375);
WIRE 16 -1 (-2500 4375)(-2075 4375);
WIRE 16 -1 (-2500 4025)(-2500 4375);
WIRE 16 -1 (-2075 4375)(-1925 4375);
WIRE 16 -1 (-2075 3850)(-2075 4375);
WIRE 16 -1 (-1575 4375)(-1925 4375);
WIRE 16 -1 (-1925 4200)(-1925 4375);
WIRE 16 -1 (-1575 4300)(-1575 4375);
WIRE 16 -1 (-375 2275)(-375 2175);
WIRE 16 -1 (-825 2175)(-375 2175);
WIRE 16 -1 (-1100 2175)(-825 2175);
WIRE 16 -1 (-825 2100)(-825 2175);
WIRE 16 -1 (-1100 2175)(-1100 2100);
WIRE 16 -1 (-3025 825)(-2900 825);
WIRE 16 -1 (-1450 1975)(-1450 1900);
WIRE 16 -1 (-1275 3850)(-1275 3900);
WIRE 16 -1 (-1475 850)(-1475 900);
WIRE 16 -1 (-1875 850)(-1875 900);
WIRE 16 -1 (-3075 1600)(-3075 1825);
WIRE 16 -1 (-3350 1825)(-3075 1825);
WIRE 16 -1 (-3550 3775)(-3550 3825);
WIRE 16 -1 (-3950 3775)(-3950 3825);
WIRE 16 -1 (-4400 625)(-4400 800);
WIRE 16 -1 (-4725 625)(-4725 800);
WIRE 16 -1 (-5325 4475)(-5325 4775);
WIRE 16 -1 (-4775 4475)(-5325 4475);
WIRE 16 -1 (-5325 4475)(-5650 4475);
WIRE 16 -1 (-5650 4375)(-5650 4475);
WIRE 16 -1 (-4775 4450)(-4775 4475);
WIRE 16 -1 (-6050 4775)(-6050 4725);
WIRE 16 -1 (-6050 4025)(-6050 4100);
WIRE 16 -1 (-6600 4075)(-6600 4100);
WIRE 16 -1 (-5425 1075)(-5425 1175);
WIRE 16 -1 (-5125 825)(-5125 900);
WIRE 16 -1 (-4450 3275)(-4250 3275);
WIRE 16 -1 (-4450 3950)(-4450 3275);
WIRE 16 -1 (-5300 3950)(-4450 3950);
FORCEPROP 2 LAST SIG_NAME SVID_VCLK_PVCCIN_CPU0
J 0
(-5190 3965);
DISPLAY 0.617021 (-5190 3965);
PAINT ORANGE (-5190 3965);
FORCEPROP 2 LASTPROP $XRERR UNIQUE?
J 0
(-5430 3965);
DISPLAY 0.638298 (-5430 3965);
PAINT MONO (-5430 3965);
DISPLAY INVISIBLE (-5430 3965);
WIRE 16 -1 (-3350 2975)(-3050 2975);
WIRE 16 -1 (-2500 2975)(-3050 2975);
FORCEPROP 2 LAST SIG_NAME IRQ_PVCCIN_CPU0_VRHOT_LVC3_R_N
J 0
(-3240 2990);
DISPLAY 0.617021 (-3240 2990);
PAINT ORANGE (-3240 2990);
FORCEPROP 2 LASTPROP $XRERR UNIQUE?
J 0
(-3480 2990);
DISPLAY 0.638298 (-3480 2990);
PAINT MONO (-3480 2990);
DISPLAY INVISIBLE (-3480 2990);
WIRE 16 -1 (-3050 4025)(-3050 2975);
WIRE 3 682 (-2775 625)(-3400 625);
WIRE 3 682 (-2775 1175)(-2775 625);
WIRE 3 682 (-3400 625)(-3400 1175);
WIRE 3 682 (-3400 1175)(-2775 1175);
WIRE 3 2175 (-8050 3425)(-8050 3875);
WIRE 3 2175 (-8050 3875)(-7000 3875);
WIRE 3 2175 (-8050 3425)(-7000 3425);
WIRE 3 2175 (-7000 3425)(-7000 3875);
WIRE 16 -1 (-3350 2375)(-1100 2375);
FORCEPROP 0 LAST VOLTAGE 3.6
J 0
(-1775 2450);
DISPLAY 1.021277 (-1775 2450);
PAINT SKYBLUE (-1775 2450);
DISPLAY INVISIBLE (-1775 2450);
FORCEPROP 2 LAST SIG_NAME VR_PVCCIN_CPU0_PWM3
J 0
(-1790 2390);
DISPLAY 0.617021 (-1790 2390);
PAINT ORANGE (-1790 2390);
WIRE 16 -1 (-5500 3950)(-5650 3950);
WIRE 16 -1 (-5650 4175)(-5650 3950);
WIRE 16 -1 (-7350 3950)(-5650 3950);
FORCEPROP 2 LAST SIG_NAME SVID_CLK0_CPU0_R
J 0
(-7350 3960);
DISPLAY 0.617021 (-7350 3960);
PAINT ORANGE (-7350 3960);
WIRE 16 -1 (-5875 1325)(-6000 1325);
WIRE 16 -1 (-6000 1425)(-5900 1425);
WIRE 16 -1 (-6000 1325)(-6000 1425);
WIRE 16 -1 (-6000 1525)(-7350 1525);
FORCEPROP 2 LAST SIG_NAME VR_PVSA_CPU0_BIREF1
J 0
(-7327 1541);
DISPLAY 0.617021 (-7327 1541);
PAINT ORANGE (-7327 1541);
WIRE 16 -1 (-6000 1425)(-6000 1525);
WIRE 16 -1 (-5075 1525)(-6000 1525);
WIRE 16 -1 (-5075 1875)(-5075 1525);
WIRE 16 -1 (-4250 1875)(-5075 1875);
WIRE 3 2175 (-6600 1400)(-6100 1400);
WIRE 3 2175 (-6100 1150)(-6100 1400);
WIRE 3 2175 (-6600 1150)(-6600 1400);
WIRE 3 2175 (-6600 1150)(-6100 1150);
WIRE 3 2175 (-6050 1650)(-5475 1650);
WIRE 3 2175 (-5475 1025)(-5475 1650);
WIRE 3 2175 (-6050 1025)(-6050 1650);
WIRE 3 2175 (-6050 1025)(-5475 1025);
WIRE 3 682 (-5400 4550)(-5750 4550);
WIRE 3 682 (-5400 4100)(-5400 4550);
WIRE 3 682 (-5750 4100)(-5750 4550);
WIRE 3 682 (-5750 4100)(-5400 4100);
WIRE 3 682 (-6950 3750)(-4800 3750);
WIRE 3 682 (-4800 3750)(-4800 3875);
WIRE 3 682 (-6950 3875)(-6950 3750);
WIRE 3 682 (-6950 3875)(-4800 3875);
WIRE 3 2175 (-6950 2950)(-4800 2950);
WIRE 3 2175 (-4800 3700)(-4800 2950);
WIRE 3 2175 (-6950 3700)(-6950 2950);
WIRE 3 2175 (-6950 3700)(-4800 3700);
WIRE 16 -1 (-7575 2675)(-4875 2675);
FORCEPROP 2 LAST SIG_NAME ISENSE_PVCCIN_CPU0_PH5_IMON
J 0
(-7565 2690);
DISPLAY 0.617021 (-7565 2690);
PAINT ORANGE (-7565 2690);
WIRE 16 -1 (-4250 2675)(-4875 2675);
WIRE 16 -1 (-4875 2675)(-4875 3350);
WIRE 16 -1 (-4950 3350)(-4875 3350);
WIRE 16 -1 (-4875 3500)(-4875 3350);
WIRE 16 -1 (-4875 3500)(-4925 3500);
WIRE 16 -1 (-4950 2225)(-5000 2225);
WIRE 16 -1 (-4250 2225)(-4950 2225);
WIRE 16 -1 (-4950 2925)(-4950 2225);
FORCEPROP 2 LAST SIG_NAME VR_PVCCIN_CPU0_VREN
J 0
(-4915 2240);
DISPLAY 0.617021 (-4915 2240);
PAINT ORANGE (-4915 2240);
FORCEPROP 2 LASTPROP $XRERR UNIQUE?
J 0
(-5155 2240);
DISPLAY 0.638298 (-5155 2240);
PAINT MONO (-5155 2240);
DISPLAY INVISIBLE (-5155 2240);
WIRE 16 -1 (-4775 2925)(-4950 2925);
WIRE 16 -1 (-4775 2925)(-4775 4250);
FORCEPROP 0 LAST VOLTAGE 3.3
J 0
(-4775 3650);
DISPLAY 1.021277 (-4775 3650);
PAINT SKYBLUE (-4775 3650);
DISPLAY INVISIBLE (-4775 3650);
WIRE 16 -1 (-2425 2125)(-3350 2125);
WIRE 16 -1 (-1100 1900)(-1100 1775);
WIRE 16 -1 (-1100 1775)(-750 1775);
WIRE 16 -1 (-2425 1775)(-2425 2125);
WIRE 16 -1 (-1650 1775)(-2425 1775);
WIRE 16 -1 (-1650 1775)(-1100 1775);
FORCEPROP 2 LAST SIG_NAME SMB_VR_STBY_LVC3_SDA
J 0
(-1465 1790);
DISPLAY 0.617021 (-1465 1790);
PAINT ORANGE (-1465 1790);
WIRE 16 -1 (-1650 1350)(-1650 1775);
WIRE 16 -1 (-2225 1350)(-1650 1350);
WIRE 16 -1 (-3025 925)(-2225 925);
WIRE 16 -1 (-2225 925)(-2225 1350);
WIRE 16 -1 (-2500 2025)(-3350 2025);
WIRE 16 -1 (-825 1525)(-750 1525);
WIRE 16 -1 (-825 1900)(-825 1525);
WIRE 16 -1 (-2500 2025)(-2500 1525);
WIRE 16 -1 (-1575 1525)(-2500 1525);
WIRE 16 -1 (-1575 1525)(-825 1525);
FORCEPROP 2 LAST SIG_NAME SMB_VR_STBY_LVC3_SCL
J 0
(-1465 1540);
DISPLAY 0.617021 (-1465 1540);
PAINT ORANGE (-1465 1540);
WIRE 16 -1 (-2975 775)(-3025 775);
WIRE 16 -1 (-2975 775)(-2975 725);
WIRE 16 -1 (-1575 1275)(-1575 1525);
WIRE 16 -1 (-2075 1275)(-1575 1275);
WIRE 16 -1 (-2975 725)(-2075 725);
WIRE 16 -1 (-2075 725)(-2075 1275);
WIRE 16 -1 (-6450 2250)(-7350 2250);
FORCEPROP 2 LAST SIG_NAME VSENSE_PVCCIN_CPU0_N
J 0
(-7365 2265);
DISPLAY 0.617021 (-7365 2265);
PAINT ORANGE (-7365 2265);
WIRE 16 -1 (-6450 2275)(-6450 2250);
WIRE 16 -1 (-6050 2250)(-6450 2250);
WIRE 16 -1 (-6050 2475)(-6050 2250);
WIRE 16 -1 (-4250 2475)(-6050 2475);
WIRE 16 -1 (-6575 2525)(-6450 2525);
WIRE 16 -1 (-6450 2475)(-6450 2525);
WIRE 16 -1 (-4250 2525)(-6450 2525);
FORCEPROP 2 LAST SIG_NAME VSENSE_PVCCIN_CPU0_AVSP
J 0
(-5640 2540);
DISPLAY 0.617021 (-5640 2540);
PAINT ORANGE (-5640 2540);
FORCEPROP 2 LASTPROP $XRERR UNIQUE?
J 0
(-5880 2540);
DISPLAY 0.638298 (-5880 2540);
PAINT MONO (-5880 2540);
DISPLAY INVISIBLE (-5880 2540);
WIRE 16 -1 (-6150 2075)(-5975 2075);
WIRE 16 -1 (-5975 2075)(-5975 2275);
WIRE 16 -1 (-5975 2275)(-5550 2275);
WIRE 16 -1 (-5550 2175)(-5550 2275);
WIRE 16 -1 (-5550 2275)(-5550 2425);
FORCEPROP 2 LAST SIG_NAME VSENSE_PVSA_CPU0_BVSP
J 0
(-5590 2440);
DISPLAY 0.617021 (-5590 2440);
PAINT ORANGE (-5590 2440);
FORCEPROP 2 LASTPROP $XRERR UNIQUE?
J 0
(-5830 2440);
DISPLAY 0.638298 (-5830 2440);
PAINT MONO (-5830 2440);
DISPLAY INVISIBLE (-5830 2440);
WIRE 16 -1 (-5550 2425)(-4250 2425);
WIRE 16 -1 (-5275 3500)(-5325 3500);
WIRE 16 -1 (-5350 3350)(-5275 3350);
WIRE 16 -1 (-5275 3500)(-5275 3350);
WIRE 16 -1 (-7575 2725)(-5275 2725);
FORCEPROP 2 LAST SIG_NAME ISENSE_PVCCIN_CPU0_PH4_IMON
J 0
(-7565 2740);
DISPLAY 0.617021 (-7565 2740);
PAINT ORANGE (-7565 2740);
WIRE 16 -1 (-5275 2725)(-5275 3350);
WIRE 16 -1 (-4250 2725)(-5275 2725);
WIRE 16 -1 (-5650 3500)(-5725 3500);
WIRE 16 -1 (-5750 3350)(-5650 3350);
WIRE 16 -1 (-5650 3500)(-5650 3350);
WIRE 16 -1 (-7575 2775)(-5650 2775);
FORCEPROP 2 LAST SIG_NAME ISENSE_PVCCIN_CPU0_PH3_IMON
J 0
(-7565 2790);
DISPLAY 0.617021 (-7565 2790);
PAINT ORANGE (-7565 2790);
WIRE 16 -1 (-5650 2775)(-5650 3350);
WIRE 16 -1 (-5650 2775)(-4250 2775);
WIRE 16 -1 (-6200 3500)(-6100 3500);
WIRE 16 -1 (-6225 3350)(-6100 3350);
WIRE 16 -1 (-6100 3500)(-6100 3350);
WIRE 16 -1 (-7575 2825)(-6100 2825);
FORCEPROP 2 LAST SIG_NAME ISENSE_PVCCIN_CPU0_PH2_IMON
J 0
(-7565 2840);
DISPLAY 0.617021 (-7565 2840);
PAINT ORANGE (-7565 2840);
WIRE 16 -1 (-6100 2825)(-6100 3350);
WIRE 16 -1 (-6100 2825)(-4250 2825);
WIRE 16 -1 (-5125 3500)(-5175 3500);
WIRE 16 -1 (-5175 3500)(-5175 3350);
WIRE 16 -1 (-5100 3350)(-5175 3350);
WIRE 16 -1 (-5175 2975)(-5175 3350);
WIRE 16 -1 (-4250 2975)(-5175 2975);
WIRE 16 -1 (-7575 2975)(-5175 2975);
FORCEPROP 2 LAST SIG_NAME VR_PVCCIN_CPU0_AIREF5
J 0
(-7540 2990);
DISPLAY 0.617021 (-7540 2990);
PAINT ORANGE (-7540 2990);
WIRE 16 -1 (-5575 3500)(-5525 3500);
WIRE 16 -1 (-5575 3500)(-5575 3350);
WIRE 16 -1 (-5500 3350)(-5575 3350);
WIRE 16 -1 (-7575 3025)(-5575 3025);
FORCEPROP 2 LAST SIG_NAME VR_PVCCIN_CPU0_AIREF4
J 0
(-7540 3040);
DISPLAY 0.617021 (-7540 3040);
PAINT ORANGE (-7540 3040);
WIRE 16 -1 (-5575 3025)(-5575 3350);
WIRE 16 -1 (-4250 3025)(-5575 3025);
WIRE 16 -1 (-5925 3500)(-6000 3500);
WIRE 16 -1 (-5900 3350)(-6000 3350);
WIRE 16 -1 (-6000 3500)(-6000 3350);
WIRE 16 -1 (-6000 3075)(-6000 3350);
WIRE 16 -1 (-4250 3075)(-6000 3075);
WIRE 16 -1 (-7575 3075)(-6000 3075);
FORCEPROP 2 LAST SIG_NAME VR_PVCCIN_CPU0_AIREF3
J 0
(-7540 3090);
DISPLAY 0.617021 (-7540 3090);
PAINT ORANGE (-7540 3090);
WIRE 16 -1 (-6850 3500)(-6900 3500);
WIRE 16 -1 (-6825 3350)(-6900 3350);
WIRE 16 -1 (-6900 3500)(-6900 3350);
WIRE 16 -1 (-6900 3175)(-6900 3350);
WIRE 16 -1 (-4250 3175)(-6900 3175);
WIRE 16 -1 (-7575 3175)(-6900 3175);
FORCEPROP 2 LAST SIG_NAME VR_PVCCIN_CPU0_AIREF1
J 0
(-7540 3190);
DISPLAY 0.617021 (-7540 3190);
PAINT ORANGE (-7540 3190);
WIRE 16 -1 (-6475 3500)(-6400 3500);
WIRE 16 -1 (-6475 3500)(-6475 3350);
WIRE 16 -1 (-6375 3350)(-6475 3350);
WIRE 16 -1 (-6475 3125)(-6475 3350);
WIRE 16 -1 (-4250 3125)(-6475 3125);
WIRE 16 -1 (-7575 3125)(-6475 3125);
FORCEPROP 2 LAST SIG_NAME VR_PVCCIN_CPU0_AIREF2
J 0
(-7540 3140);
DISPLAY 0.617021 (-7540 3140);
PAINT ORANGE (-7540 3140);
WIRE 16 -1 (-6600 3500)(-6650 3500);
WIRE 16 -1 (-6675 3350)(-6600 3350);
WIRE 16 -1 (-6600 3500)(-6600 3350);
WIRE 16 -1 (-6600 2875)(-6600 3350);
WIRE 16 -1 (-4250 2875)(-6600 2875);
WIRE 16 -1 (-7575 2875)(-6600 2875);
FORCEPROP 2 LAST SIG_NAME ISENSE_PVCCIN_CPU0_PH1_IMON
J 0
(-7565 2890);
DISPLAY 0.617021 (-7565 2890);
PAINT ORANGE (-7565 2890);
WIRE 16 -1 (-3350 3225)(-1925 3225);
WIRE 16 -1 (-1925 4000)(-1925 3225);
WIRE 16 -1 (-1925 3075)(-1925 3225);
WIRE 16 -1 (-1100 3075)(-1925 3075);
FORCEPROP 0 LAST SIG_NAME FM_PVCCIN_CPU0_PWR_IN_ALERT_N
J 0
(-1800 3090);
DISPLAY 0.617021 (-1800 3090);
PAINT ORANGE (-1800 3090);
WIRE 16 -1 (-4250 4075)(-4250 3375);
WIRE 16 -1 (-4250 4175)(-4250 4075);
WIRE 16 -1 (-3950 4075)(-4250 4075);
FORCEPROP 0 LAST VOLTAGE 3.3
J 0
(-4100 4125);
DISPLAY 1.021277 (-4100 4125);
PAINT SKYBLUE (-4100 4125);
DISPLAY INVISIBLE (-4100 4125);
WIRE 16 -1 (-3950 4025)(-3950 4075);
WIRE 16 -1 (-3550 4075)(-3950 4075);
FORCEPROP 2 LAST SIG_NAME VR_PVCCIN_CPU0_VDD
J 0
(-4015 4090);
DISPLAY 0.617021 (-4015 4090);
PAINT ORANGE (-4015 4090);
FORCEPROP 2 LASTPROP $XRERR UNIQUE?
J 0
(-4255 4090);
DISPLAY 0.638298 (-4255 4090);
PAINT MONO (-4255 4090);
DISPLAY INVISIBLE (-4255 4090);
WIRE 16 -1 (-3550 4025)(-3550 4075);
WIRE 16 -1 (-5125 1925)(-4250 1925);
WIRE 16 -1 (-5125 1100)(-5125 1575);
WIRE 16 -1 (-5125 1575)(-5125 1925);
WIRE 16 -1 (-7350 1575)(-5125 1575);
FORCEPROP 2 LAST SIG_NAME A_TSENSE_PVSA_CPU0
J 0
(-7340 1590);
DISPLAY 0.617021 (-7340 1590);
PAINT ORANGE (-7340 1590);
WIRE 16 -1 (-3350 2475)(-1100 2475);
FORCEPROP 0 LAST VOLTAGE 3.6
J 0
(-1775 2550);
DISPLAY 1.021277 (-1775 2550);
PAINT SKYBLUE (-1775 2550);
DISPLAY INVISIBLE (-1775 2550);
FORCEPROP 2 LAST SIG_NAME VR_PVCCIN_CPU0_PWM1
J 0
(-1790 2490);
DISPLAY 0.617021 (-1790 2490);
PAINT ORANGE (-1790 2490);
WIRE 16 -1 (-1100 2975)(-2300 2975);
FORCEPROP 2 LAST SIG_NAME IRQ_PVCCIN_CPU0_VRHOT_LVC3_N
J 0
(-1890 2990);
DISPLAY 0.617021 (-1890 2990);
PAINT ORANGE (-1890 2990);
WIRE 16 -1 (-2775 3825)(-2775 2675);
WIRE 16 -1 (-2775 2675)(-1900 2675);
WIRE 16 -1 (-3350 2675)(-2775 2675);
FORCEPROP 2 LAST SIG_NAME PWRGD_PVSA_CPU0_R
J 0
(-3240 2690);
DISPLAY 0.617021 (-3240 2690);
PAINT ORANGE (-3240 2690);
FORCEPROP 2 LASTPROP $XRERR UNIQUE?
J 0
(-3480 2690);
DISPLAY 0.638298 (-3480 2690);
PAINT MONO (-3480 2690);
DISPLAY INVISIBLE (-3480 2690);
WIRE 16 -1 (-3350 2775)(-1100 2775);
FORCEPROP 2 LAST SIG_NAME VR_PVCCIN_CPU0_VD12
J 0
(-1790 2790);
DISPLAY 0.617021 (-1790 2790);
PAINT ORANGE (-1790 2790);
WIRE 16 -1 (-2125 2875)(-3350 2875);
FORCEPROP 2 LAST SIG_NAME SVID_VALERT_VCCIN_CPU0
J 0
(-3240 2890);
DISPLAY 0.617021 (-3240 2890);
PAINT ORANGE (-3240 2890);
FORCEPROP 2 LASTPROP $XRERR UNIQUE?
J 0
(-3480 2890);
DISPLAY 0.638298 (-3480 2890);
PAINT MONO (-3480 2890);
DISPLAY INVISIBLE (-3480 2890);
WIRE 16 -1 (-2075 3650)(-2075 3125);
WIRE 16 -1 (-3350 3125)(-2075 3125);
FORCEPROP 2 LAST SIG_NAME PU_VR_PVCCIN_CPU0_IMON
J 0
(-3240 3140);
DISPLAY 0.617021 (-3240 3140);
PAINT ORANGE (-3240 3140);
FORCEPROP 2 LASTPROP $XRERR UNIQUE?
J 0
(-3480 3140);
DISPLAY 0.638298 (-3480 3140);
PAINT MONO (-3480 3140);
DISPLAY INVISIBLE (-3480 3140);
WIRE 16 -1 (-1575 3275)(-1575 4100);
WIRE 16 -1 (-3350 3275)(-1575 3275);
FORCEPROP 2 LAST SIG_NAME PU_VR_PVCCIN_CPU0_FLT1_SMBALT_N_IMON
J 0
(-3240 3290);
DISPLAY 0.617021 (-3240 3290);
PAINT ORANGE (-3240 3290);
FORCEPROP 2 LASTPROP $XRERR UNIQUE?
J 0
(-3480 3290);
DISPLAY 0.638298 (-3480 3290);
PAINT MONO (-3480 3290);
DISPLAY INVISIBLE (-3480 3290);
WIRE 16 -1 (-2500 2725)(-3350 2725);
FORCEPROP 0 LAST SIG_NAME SVID_VDIO_PVCCIN_CPU0
J 0
(-3235 2735);
DISPLAY 0.617021 (-3235 2735);
PAINT ORANGE (-3235 2735);
FORCEPROP 2 LASTPROP $XRERR UNIQUE?
J 0
(-3475 2735);
DISPLAY 0.638298 (-3475 2735);
PAINT MONO (-3475 2735);
DISPLAY INVISIBLE (-3475 2735);
WIRE 16 -1 (-1700 2675)(-1100 2675);
FORCEPROP 2 LAST SIG_NAME PWRGD_PVSA_CPU0
J 0
(-1715 2690);
DISPLAY 0.617021 (-1715 2690);
PAINT ORANGE (-1715 2690);
WIRE 16 -1 (-3350 2525)(-1100 2525);
FORCEPROP 2 LAST SIG_NAME VR_PVSA_CPU0_PWM
J 0
(-1790 2540);
DISPLAY 0.617021 (-1790 2540);
PAINT ORANGE (-1790 2540);
WIRE 16 -1 (-1450 2175)(-1450 3325);
WIRE 16 -1 (-1450 3325)(-1225 3325);
WIRE 16 -1 (-2500 3825)(-2500 3325);
WIRE 16 -1 (-2500 3325)(-1450 3325);
FORCEPROP 0 LAST VOLTAGE 3.3
J 0
(-1975 3375);
DISPLAY 1.021277 (-1975 3375);
PAINT SKYBLUE (-1975 3375);
DISPLAY INVISIBLE (-1975 3375);
WIRE 16 -1 (-3350 3325)(-2500 3325);
FORCEPROP 2 LAST SIG_NAME VR_VRRDY_PVCCIN_CPU0
J 0
(-3240 3340);
DISPLAY 0.617021 (-3240 3340);
PAINT ORANGE (-3240 3340);
FORCEPROP 2 LASTPROP $XRERR UNIQUE?
J 0
(-3480 3340);
DISPLAY 0.638298 (-3480 3340);
PAINT MONO (-3480 3340);
DISPLAY INVISIBLE (-3480 3340);
WIRE 3 682 (-2000 3925)(-1650 3925);
WIRE 3 682 (-2000 4300)(-2000 3925);
WIRE 3 682 (-1650 3925)(-1650 4300);
WIRE 3 682 (-1650 4300)(-2000 4300);
WIRE 16 -1 (-5375 2275)(-4250 2275);
WIRE 16 -1 (-5375 1875)(-5375 2275);
WIRE 16 -1 (-5425 1375)(-5425 1875);
WIRE 16 -1 (-5425 1875)(-5375 1875);
WIRE 16 -1 (-7350 1875)(-5425 1875);
FORCEPROP 2 LAST SIG_NAME A_TSENSE_PVCCIN_CPU0
J 0
(-7365 1890);
DISPLAY 0.617021 (-7365 1890);
PAINT ORANGE (-7365 1890);
WIRE 16 -1 (-5725 1325)(-5575 1325);
WIRE 16 -1 (-4250 1825)(-5025 1825);
WIRE 16 -1 (-5025 1825)(-5025 1475);
WIRE 16 -1 (-5700 1425)(-5575 1425);
WIRE 16 -1 (-5575 1325)(-5575 1425);
WIRE 16 -1 (-5575 1425)(-5575 1475);
WIRE 16 -1 (-5025 1475)(-5575 1475);
WIRE 16 -1 (-7350 1475)(-5575 1475);
FORCEPROP 2 LAST SIG_NAME ISENSE_PVSA_CPU0_IMON
J 0
(-7340 1490);
DISPLAY 0.617021 (-7340 1490);
PAINT ORANGE (-7340 1490);
WIRE 16 -1 (-3350 2275)(-1100 2275);
FORCEPROP 0 LAST VOLTAGE 3.6
J 0
(-1775 2350);
DISPLAY 1.021277 (-1775 2350);
PAINT SKYBLUE (-1775 2350);
DISPLAY INVISIBLE (-1775 2350);
FORCEPROP 2 LAST SIG_NAME VR_PVCCIN_CPU0_PWM5
J 0
(-1790 2290);
DISPLAY 0.617021 (-1790 2290);
PAINT ORANGE (-1790 2290);
WIRE 16 -1 (-3350 2325)(-1100 2325);
FORCEPROP 0 LAST VOLTAGE 3.6
J 0
(-1775 2400);
DISPLAY 1.021277 (-1775 2400);
PAINT SKYBLUE (-1775 2400);
DISPLAY INVISIBLE (-1775 2400);
FORCEPROP 2 LAST SIG_NAME VR_PVCCIN_CPU0_PWM4
J 0
(-1790 2340);
DISPLAY 0.617021 (-1790 2340);
PAINT ORANGE (-1790 2340);
WIRE 16 -1 (-3350 2425)(-1100 2425);
FORCEPROP 0 LAST VOLTAGE 3.6
J 0
(-1775 2500);
DISPLAY 1.021277 (-1775 2500);
PAINT SKYBLUE (-1775 2500);
DISPLAY INVISIBLE (-1775 2500);
FORCEPROP 2 LAST SIG_NAME VR_PVCCIN_CPU0_PWM2
J 0
(-1790 2440);
DISPLAY 0.617021 (-1790 2440);
PAINT ORANGE (-1790 2440);
WIRE 16 -1 (-6600 4425)(-7325 4425);
FORCEPROP 0 LAST VOLTAGE 0.8
J 0
(-7325 4500);
DISPLAY 1.021277 (-7325 4500);
PAINT SKYBLUE (-7325 4500);
DISPLAY INVISIBLE (-7325 4500);
FORCEPROP 2 LAST SIG_NAME VR_PVCCIN_CPU0_AVINSEN
J 0
(-7340 4440);
DISPLAY 0.617021 (-7340 4440);
PAINT ORANGE (-7340 4440);
WIRE 16 -1 (-6600 4300)(-6600 4425);
WIRE 16 -1 (-6050 4425)(-6600 4425);
WIRE 16 -1 (-6050 4300)(-6050 4425);
WIRE 16 -1 (-6050 4425)(-6050 4525);
WIRE 3 682 (-6700 4000)(-6150 4000);
WIRE 3 682 (-6700 4500)(-6700 4000);
WIRE 3 682 (-6150 4000)(-6150 4500);
WIRE 3 682 (-6150 4500)(-6700 4500);
WIRE 16 -1 (-5250 2175)(-4250 2175);
WIRE 16 -1 (-5250 1725)(-5250 2175);
WIRE 16 -1 (-7350 1725)(-5250 1725);
FORCEPROP 0 LAST VOLTAGE 0.8
J 0
(-7325 1800);
DISPLAY 1.021277 (-7325 1800);
PAINT SKYBLUE (-7325 1800);
DISPLAY INVISIBLE (-7325 1800);
FORCEPROP 2 LAST SIG_NAME VR_PVCCIN_CPU0_AVINSEN
J 0
(-7340 1740);
DISPLAY 0.617021 (-7340 1740);
PAINT ORANGE (-7340 1740);
WIRE 3 682 (-2150 1850)(-2150 1475);
WIRE 3 682 (-1800 1850)(-2150 1850);
WIRE 3 682 (-2150 1475)(-1800 1475);
WIRE 3 682 (-1800 1475)(-1800 1850);
WIRE 3 682 (-1400 4050)(-1400 3500);
WIRE 3 682 (-950 4050)(-1400 4050);
WIRE 3 682 (-1400 3500)(-950 3500);
WIRE 3 682 (-950 3500)(-950 4050);
WIRE 16 -1 (-1925 2875)(-1100 2875);
FORCEPROP 2 LAST SIG_NAME SVID_ALERT0_CPU0_R_N
J 0
(-1800 2885);
DISPLAY 0.617021 (-1800 2885);
PAINT ORANGE (-1800 2885);
WIRE 16 -1 (-7325 2525)(-6775 2525);
FORCEPROP 2 LAST SIG_NAME VSENSE_PVCCIN_CPU0_P
J 0
(-7340 2540);
DISPLAY 0.617021 (-7340 2540);
PAINT ORANGE (-7340 2540);
WIRE 16 -1 (-1025 3325)(-500 3325);
FORCEPROP 2 LAST SIG_NAME PWRGD_PVCCIN_CPU0
J 0
(-965 3340);
DISPLAY 0.617021 (-965 3340);
PAINT ORANGE (-965 3340);
WIRE 16 -1 (-7350 2075)(-6350 2075);
FORCEPROP 2 LAST SIG_NAME VSENSE_PVSA_CPU0_P
J 0
(-7365 2090);
DISPLAY 0.617021 (-7365 2090);
PAINT ORANGE (-7365 2090);
WIRE 16 -1 (-1125 2725)(-1275 2725);
WIRE 16 -1 (-1275 3650)(-1275 2725);
WIRE 16 -1 (-2300 2725)(-1275 2725);
FORCEPROP 0 LAST SIG_NAME SVID_DIO0_CPU0_R
J 0
(-1775 2735);
DISPLAY 0.617021 (-1775 2735);
PAINT ORANGE (-1775 2735);
WIRE 3 682 (-4350 2025)(-4300 2025);
WIRE 3 682 (-4350 2125)(-4350 2025);
WIRE 3 682 (-4300 2125)(-4350 2125);
WIRE 16 -1 (-5550 1925)(-7350 1925);
FORCEPROP 2 LAST SIG_NAME VSENSE_PVSA_CPU0_N
J 0
(-7365 1940);
DISPLAY 0.617021 (-7365 1940);
PAINT ORANGE (-7365 1940);
WIRE 16 -1 (-5550 1975)(-5550 1925);
WIRE 16 -1 (-5450 1925)(-5550 1925);
WIRE 16 -1 (-5450 2375)(-5450 1925);
WIRE 16 -1 (-4250 2375)(-5450 2375);
WIRE 16 -1 (-5200 2225)(-5300 2225);
WIRE 16 -1 (-5300 1825)(-5300 2225);
WIRE 16 -1 (-7350 1825)(-5300 1825);
FORCEPROP 2 LAST SIG_NAME FM_PVCCIN_PVCCSA_CPU0_EN_LVC1
J 0
(-7343 1826);
DISPLAY 0.617021 (-7343 1826);
PAINT ORANGE (-7343 1826);
WIRE 16 -1 (-1875 1100)(-1875 1175);
WIRE 16 -1 (-1475 1175)(-1875 1175);
FORCEPROP 2 LAST SIG_NAME VR_PVCCIN_CPU0_VD12
J 0
(-1790 1190);
DISPLAY 0.617021 (-1790 1190);
PAINT ORANGE (-1790 1190);
WIRE 16 -1 (-1475 1175)(-1125 1175);
WIRE 16 -1 (-1475 1100)(-1475 1175);
WIRE 16 -1 (-4725 1775)(-4250 1775);
FORCEPROP 0 LAST VOLTAGE 3.3
J 0
(-4475 1825);
DISPLAY 1.021277 (-4475 1825);
PAINT SKYBLUE (-4475 1825);
DISPLAY INVISIBLE (-4475 1825);
WIRE 16 -1 (-4725 1000)(-4725 1775);
FORCEPROP 0 LAST SIG_NAME VR_PVCCIN_CPU0_XADDR1
R 1
J 0
(-4735 1060);
DISPLAY 0.617021 (-4735 1060);
PAINT ORANGE (-4735 1060);
FORCEPROP 2 LASTPROP $XRERR UNIQUE?
J 0
(-4975 1060);
DISPLAY 0.638298 (-4975 1060);
PAINT MONO (-4975 1060);
DISPLAY INVISIBLE (-4975 1060);
WIRE 16 -1 (-4400 1725)(-4250 1725);
WIRE 16 -1 (-4400 1000)(-4400 1725);
FORCEPROP 0 LAST VOLTAGE 3.3
J 0
(-4400 1125);
DISPLAY 1.021277 (-4400 1125);
PAINT SKYBLUE (-4400 1125);
DISPLAY INVISIBLE (-4400 1125);
FORCEPROP 0 LAST SIG_NAME VR_PVCCIN_CPU0_XADDR2
R 1
J 0
(-4410 1060);
DISPLAY 0.617021 (-4410 1060);
PAINT ORANGE (-4410 1060);
FORCEPROP 2 LASTPROP $XRERR UNIQUE?
J 0
(-4650 1060);
DISPLAY 0.638298 (-4650 1060);
PAINT MONO (-4650 1060);
DISPLAY INVISIBLE (-4650 1060);
DOT 1 (-6000 3075);
DOT 1 (-6900 3175);
DOT 1 (-6100 3350);
DOT 1 (-6000 3350);
DOT 1 (-6900 3350);
DOT 1 (-6600 3350);
DOT 1 (-6475 3350);
DOT 1 (-5650 3350);
DOT 1 (-5575 3350);
DOT 1 (-5275 3350);
DOT 1 (-5175 3350);
DOT 1 (-4875 3350);
DOT 1 (-6600 4425);
DOT 1 (-6050 4425);
DOT 1 (-5325 4475);
DOT 1 (-5425 1875);
DOT 1 (-6000 1525);
DOT 1 (-6000 1425);
DOT 1 (-5575 1425);
DOT 1 (-1450 3325);
DOT 1 (-3050 2975);
DOT 1 (-2775 2675);
DOT 1 (-1925 3225);
DOT 1 (-6100 2825);
DOT 1 (-5275 2725);
DOT 1 (-6450 2525);
DOT 1 (-1925 4375);
DOT 1 (-2075 4375);
DOT 1 (-2500 4375);
DOT 1 (-2775 4375);
DOT 1 (-3050 4375);
DOT 1 (-1275 2725);
DOT 1 (-1100 1775);
DOT 1 (-1475 1175);
DOT 1 (-1575 1525);
DOT 1 (-2500 3325);
DOT 1 (-3950 4075);
DOT 1 (-4250 4075);
DOT 1 (-5550 2275);
DOT 1 (-6450 2250);
DOT 1 (-5175 2975);
DOT 1 (-5125 1575);
DOT 1 (-825 2175);
DOT 1 (-825 1525);
DOT 1 (-4875 2675);
DOT 1 (-4950 2225);
DOT 1 (-5575 1475);
DOT 1 (-5575 3025);
DOT 1 (-5650 2775);
DOT 1 (-1650 1775);
DOT 1 (-5550 1925);
DOT 1 (-6475 3125);
DOT 1 (-6600 2875);
DOT 1 (-5650 3950);
FORCENOTE
INFINEON:NOPOP
(-8025 3550) 0;
DISPLAY LEFT (-8025 3550);
DISPLAY 1.085106 (-8025 3550);
PAINT RED (-8025 3550);
FORCENOTE
FAIRCHILD:POP
(-8025 3450) 0;
DISPLAY LEFT (-8025 3450);
DISPLAY 1.085106 (-8025 3450);
PAINT RED (-8025 3450);
FORCENOTE
RF1&RF2&RF3&RF4&RF5&RF6
(-8025 3775) 0;
DISPLAY LEFT (-8025 3775);
DISPLAY 1.085106 (-8025 3775);
PAINT RED (-8025 3775);
FORCENOTE
CF1&CF2&CF3&CF4&CF5&CF6
(-8025 3675) 0;
DISPLAY LEFT (-8025 3675);
DISPLAY 1.085106 (-8025 3675);
PAINT RED (-8025 3675);
FORCENOTE
TP FAB1 DELETE RES 0203
(-7150 1075) 0;
DISPLAY LEFT (-7150 1075);
DISPLAY 1.021277 (-7150 1075);
PAINT RED (-7150 1075);
FORCENOTE
VR DONGLE HEADER FOR DIGITAL CONTROLLERS
(-3805 1210) 0;
DISPLAY LEFT (-3805 1210);
PAINT PURPLE (-3805 1210);
FORCENOTE
TP FAB1 CHANGE TO 021.60545.0103 0324
(-2750 600) 0;
DISPLAY LEFT (-2750 600);
DISPLAY 1.021277 (-2750 600);
PAINT RED (-2750 600);
FORCENOTE
TP FAB1 ADD ATTRIBUTE 0321
(-2750 650) 0;
DISPLAY LEFT (-2750 650);
DISPLAY 1.021277 (-2750 650);
PAINT RED (-2750 650);
FORCENOTE
TP FAB1 NC 0321
(-4900 2600) 0;
DISPLAY LEFT (-4900 2600);
DISPLAY 1.021277 (-4900 2600);
PAINT RED (-4900 2600);
FORCENOTE
TP FAB4 CHANGE RF1-5 TO 953OHM FOR VR FAILCHILD, SINGLE SIDE BOM 20170123
(-6925 2875) 0;
DISPLAY LEFT (-6925 2875);
DISPLAY 0.638298 (-6925 2875);
PAINT RED (-6925 2875);
FORCENOTE
TP FAB1 CO-LAY WITH FAIRCHILD PARTS 1203
(-6937 2906) 0;
DISPLAY LEFT (-6937 2906);
DISPLAY 0.553191 (-6937 2906);
PAINT RED (-6937 2906);
FORCENOTE
TP FAB1 CO-LAY WITH FAIRCHILD PARTS 1203
(-6912 956) 0;
DISPLAY LEFT (-6912 956);
DISPLAY 1.021277 (-6912 956);
PAINT RED (-6912 956);
FORCENOTE
TP FAB1 DELETE RES 0203
(-6850 3800) 0;
DISPLAY LEFT (-6850 3800);
DISPLAY 1.021277 (-6850 3800);
PAINT RED (-6850 3800);
FORCENOTE
TP FAB1 NOPOP RES 0316
(-5775 4550) 0;
DISPLAY LEFT (-5775 4550);
DISPLAY 1.021277 (-5775 4550);
PAINT RED (-5775 4550);
FORCENOTE
TP FAB1 DEL RES 0314
(-2400 1875) 0;
DISPLAY LEFT (-2400 1875);
DISPLAY 1.021277 (-2400 1875);
PAINT RED (-2400 1875);
FORCENOTE
TP FAB1 NC 0321
(-4900 2100) 0;
DISPLAY LEFT (-4900 2100);
DISPLAY 1.021277 (-4900 2100);
PAINT RED (-4900 2100);
FORCENOTE
ROOM=PVCCIN_CPU0_VR
(-8030 160) 0;
DISPLAY LEFT (-8030 160);
DISPLAY 1.574468 (-8030 160);
PAINT PURPLE (-8030 160);
FORCENOTE
TP FAB1 CHANGE TO 1K OHM 0218
(-2075 4400) 0;
DISPLAY LEFT (-2075 4400);
DISPLAY 1.021277 (-2075 4400);
PAINT RED (-2075 4400);
FORCENOTE
TP FAB1 NOPOP RES 0316
(-1200 4075) 0;
DISPLAY LEFT (-1200 4075);
DISPLAY 1.021277 (-1200 4075);
PAINT RED (-1200 4075);
FORCENOTE
TP FAB1 NC 0321
(-3300 2200) 0;
DISPLAY LEFT (-3300 2200);
DISPLAY 1.021277 (-3300 2200);
PAINT RED (-3300 2200);
FORCENOTE
TP FAB1 NC 0321
(-3275 2600) 0;
DISPLAY LEFT (-3275 2600);
DISPLAY 1.021277 (-3275 2600);
PAINT RED (-3275 2600);
FORCENOTE
TP FAB1 NC 0321
(-4800 2900) 0;
DISPLAY LEFT (-4800 2900);
DISPLAY 1.021277 (-4800 2900);
PAINT RED (-4800 2900);
FORCENOTE
TP FAB1 NC 0321
(-3250 3075) 0;
DISPLAY LEFT (-3250 3075);
DISPLAY 1.021277 (-3250 3075);
PAINT RED (-3250 3075);
FORCENOTE
TP FAB3 CHANGE CAP 0912
(-6700 4500) 0;
DISPLAY LEFT (-6700 4500);
DISPLAY 0.638298 (-6700 4500);
PAINT RED (-6700 4500);
QUIT
